FILE_TYPE = MACRO_DRAWING;
SET COLOR_WIRE YELLOW;
SET COLOR_PROP ORANGE;
SET COLOR_DOT WHITE;
SET COLOR_ARC YELLOW;
SET COLOR_BODY GREEN;
SET COLOR_NOTE PURPLE;
SET PROP_DISPLAY VALUE;
SET PAGE_NUMBER P144;
FORCEADD OFFPAGE..1
(-8800 850);
FORCEPROP 2 LAST $XR0 167 
J 0
(-9052 850);
DISPLAY 0.638298 (-9052 850);
PAINT MONO (-9052 850);
FORCEPROP 2 LAST CDS_LIB standard
J 0
(-8800 850);
DISPLAY INVISIBLE (-8800 850);
FORCEPROP 1 LAST OFFPAGE TRUE
J 0
(-8475 725);
DISPLAY 0.872340 (-8475 725);
PAINT GREEN (-8475 725);
DISPLAY INVISIBLE (-8475 725);
FORCEPROP 1 LAST COMMENT_BODY TRUE
J 0
(-8675 750);
DISPLAY 0.872340 (-8675 750);
PAINT GREEN (-8675 750);
DISPLAY INVISIBLE (-8675 750);
FORCEPROP 2 LAST PATH I1
J 0
(-9050 900);
DISPLAY 0.680851 (-9050 900);
DISPLAY INVISIBLE (-9050 900);
FORCEADD UNIVERSAL_GND..1
R 5
(-8200 1200);
FORCEPROP 3 LASTPIN (-8150 1200) SIG_NAME GND\g
J 0
(-8140 1210);
DISPLAY 0.659574 (-8140 1210);
PAINT MONO (-8140 1210);
DISPLAY INVISIBLE (-8140 1210);
FORCEPROP 2 LAST CDS_LIB pure_quanta_power
J 0
(-8200 1200);
DISPLAY INVISIBLE (-8200 1200);
FORCEPROP 1 LAST HDL_POWER GND
R 3
J 1
(-8275 1175);
DISPLAY 0.872340 (-8275 1175);
PAINT GREEN (-8275 1175);
DISPLAY INVISIBLE (-8275 1175);
FORCEPROP 1 LAST PATH I10
R 3
J 0
(-8200 1125);
DISPLAY 0.872340 (-8200 1125);
PAINT AQUA (-8200 1125);
DISPLAY INVISIBLE (-8200 1125);
FORCEADD OFFPAGE..5
(-8775 2350);
FORCEPROP 2 LAST $XR1 81 
J 0
(-9120 2350);
DISPLAY 0.638298 (-9120 2350);
PAINT MONO (-9120 2350);
FORCEPROP 2 LAST $XR0 167 
J 0
(-9030 2350);
DISPLAY 0.638298 (-9030 2350);
PAINT MONO (-9030 2350);
FORCEPROP 2 LAST CDS_LIB standard
J 0
(-8775 2350);
DISPLAY INVISIBLE (-8775 2350);
FORCEPROP 1 LAST OFFPAGE TRUE
J 0
(-8450 2225);
DISPLAY 0.872340 (-8450 2225);
PAINT GREEN (-8450 2225);
DISPLAY INVISIBLE (-8450 2225);
FORCEPROP 1 LAST COMMENT_BODY TRUE
J 0
(-8675 2275);
DISPLAY 0.872340 (-8675 2275);
PAINT GREEN (-8675 2275);
DISPLAY INVISIBLE (-8675 2275);
FORCEPROP 2 LAST PATH I11
J 0
(-9050 2400);
DISPLAY 0.680851 (-9050 2400);
DISPLAY INVISIBLE (-9050 2400);
FORCEADD OFFPAGE..5
(-8650 3800);
FORCEPROP 2 LAST $XR1 81 
J 0
(-9025 3800);
DISPLAY 0.638298 (-9025 3800);
PAINT MONO (-9025 3800);
FORCEPROP 2 LAST $XR0 167 
J 0
(-8935 3800);
DISPLAY 0.638298 (-8935 3800);
PAINT MONO (-8935 3800);
FORCEPROP 2 LAST CDS_LIB standard
J 0
(-8650 3800);
DISPLAY INVISIBLE (-8650 3800);
FORCEPROP 1 LAST OFFPAGE TRUE
J 0
(-8325 3675);
DISPLAY 0.872340 (-8325 3675);
PAINT GREEN (-8325 3675);
DISPLAY INVISIBLE (-8325 3675);
FORCEPROP 1 LAST COMMENT_BODY TRUE
J 0
(-8550 3725);
DISPLAY 0.872340 (-8550 3725);
PAINT GREEN (-8550 3725);
DISPLAY INVISIBLE (-8550 3725);
FORCEPROP 2 LAST PATH I12
J 0
(-8600 3875);
DISPLAY 0.680851 (-8600 3875);
DISPLAY INVISIBLE (-8600 3875);
FORCEADD OFFPAGE..5
(-8650 3900);
FORCEPROP 2 LAST $XR0 167 
J 0
(-8935 3900);
DISPLAY 0.638298 (-8935 3900);
PAINT MONO (-8935 3900);
FORCEPROP 2 LAST CDS_LIB standard
J 0
(-8650 3900);
DISPLAY INVISIBLE (-8650 3900);
FORCEPROP 1 LAST OFFPAGE TRUE
J 0
(-8325 3775);
DISPLAY 0.872340 (-8325 3775);
PAINT GREEN (-8325 3775);
DISPLAY INVISIBLE (-8325 3775);
FORCEPROP 1 LAST COMMENT_BODY TRUE
J 0
(-8550 3825);
DISPLAY 0.872340 (-8550 3825);
PAINT GREEN (-8550 3825);
DISPLAY INVISIBLE (-8550 3825);
FORCEPROP 2 LAST PATH I13
J 0
(-8600 3975);
DISPLAY 0.680851 (-8600 3975);
DISPLAY INVISIBLE (-8600 3975);
FORCEADD OFFPAGE..5
(-8900 5600);
FORCEPROP 2 LAST $XR1 81 
J 0
(-9245 5600);
DISPLAY 0.638298 (-9245 5600);
PAINT MONO (-9245 5600);
FORCEPROP 2 LAST $XR0 167 
J 0
(-9155 5600);
DISPLAY 0.638298 (-9155 5600);
PAINT MONO (-9155 5600);
FORCEPROP 2 LAST CDS_LIB standard
J 0
(-8900 5600);
DISPLAY INVISIBLE (-8900 5600);
FORCEPROP 1 LAST OFFPAGE TRUE
J 0
(-8575 5475);
DISPLAY 0.872340 (-8575 5475);
PAINT GREEN (-8575 5475);
DISPLAY INVISIBLE (-8575 5475);
FORCEPROP 1 LAST COMMENT_BODY TRUE
J 0
(-8800 5525);
DISPLAY 0.872340 (-8800 5525);
PAINT GREEN (-8800 5525);
DISPLAY INVISIBLE (-8800 5525);
FORCEPROP 2 LAST PATH I14
J 0
(-9175 5650);
DISPLAY 0.680851 (-9175 5650);
DISPLAY INVISIBLE (-9175 5650);
FORCEADD Q_RES..2
R 2
(-8200 5800);
FORCEPROP 1 LAST LOCATION R1261
J 2
(-8225 5900);
DISPLAY 0.489362 (-8225 5900);
PAINT SKYBLUE (-8225 5900);
FORCEPROP 0 LAST $SEC 1
J 0
(-8225 5950);
DISPLAY 0.680851 (-8225 5950);
PAINT MONO (-8225 5950);
DISPLAY INVISIBLE (-8225 5950);
FORCEPROP 0 LAST CDS_SEC 1
J 0
(-8225 5950);
DISPLAY 0.680851 (-8225 5950);
DISPLAY INVISIBLE (-8225 5950);
FORCEPROP 1 LASTPIN (-8200 5900) $PN 1
J 2
(-8205 5862);
DISPLAY 0.489362 (-8205 5862);
PAINT MONO (-8205 5862);
FORCEPROP 1 LASTPIN (-8200 5700) $PN 2
J 2
(-8205 5710);
DISPLAY 0.489362 (-8205 5710);
PAINT MONO (-8205 5710);
FORCEPROP 1 LAST VALUE 10K
J 2
(-8225 5700);
DISPLAY 0.489362 (-8225 5700);
PAINT SKYBLUE (-8225 5700);
FORCEPROP 1 LAST PACK_TYPE 0402LF
J 2
(-8240 5625);
DISPLAY 0.978723 (-8240 5625);
PAINT SKYBLUE (-8240 5625);
DISPLAY INVISIBLE (-8240 5625);
FORCEPROP 1 LAST TOLERANCE 5%
J 2
(-8245 5825);
DISPLAY 0.978723 (-8245 5825);
PAINT SKYBLUE (-8245 5825);
DISPLAY INVISIBLE (-8245 5825);
FORCEPROP 1 LAST MATERIAL CHIP
J 2
(-8240 5725);
DISPLAY 0.978723 (-8240 5725);
PAINT SKYBLUE (-8240 5725);
DISPLAY INVISIBLE (-8240 5725);
FORCEPROP 1 LAST WATTAGE 1/16W
J 2
(-8240 5775);
DISPLAY 0.978723 (-8240 5775);
PAINT SKYBLUE (-8240 5775);
DISPLAY INVISIBLE (-8240 5775);
FORCEPROP 2 LAST CDS_LIB pure_quanta
J 2
(-8200 5800);
DISPLAY INVISIBLE (-8200 5800);
FORCEPROP 1 LAST PATH I15
J 2
(-8250 5975);
DISPLAY 0.978723 (-8250 5975);
PAINT WHITE (-8250 5975);
DISPLAY INVISIBLE (-8250 5975);
FORCEPROP 1 LAST PART_NUMBER CS31002JB08
J 2
(-8240 5675);
DISPLAY 0.978723 (-8240 5675);
PAINT SKYBLUE (-8240 5675);
DISPLAY INVISIBLE (-8240 5675);
FORCEADD UNIVERSAL_POWER..1
R 2
(-8200 6000);
FORCEPROP 3 LASTPIN (-8200 5950) SIG_NAME P1V8_AUX\g
J 0
(-8190 5960);
DISPLAY 0.659574 (-8190 5960);
PAINT MONO (-8190 5960);
DISPLAY INVISIBLE (-8190 5960);
FORCEPROP 1 LAST HDL_POWER P1V8_AUX
J 1
(-8200 6050);
DISPLAY 0.489362 (-8200 6050);
PAINT GREEN (-8200 6050);
FORCEPROP 2 LAST CDS_LIB pure_quanta_power
J 0
(-8200 6000);
DISPLAY INVISIBLE (-8200 6000);
FORCEPROP 1 LAST PATH I16
J 2
(-8250 6025);
DISPLAY 0.872340 (-8250 6025);
PAINT AQUA (-8250 6025);
DISPLAY INVISIBLE (-8250 6025);
FORCEADD Q_RES..1
(-7600 300);
FORCEPROP 1 LAST LOCATION R744
J 0
(-7625 325);
DISPLAY 0.510638 (-7625 325);
PAINT SKYBLUE (-7625 325);
FORCEPROP 0 LAST $SEC 1
J 0
(-7550 350);
DISPLAY 0.680851 (-7550 350);
PAINT MONO (-7550 350);
DISPLAY INVISIBLE (-7550 350);
FORCEPROP 0 LAST CDS_SEC 1
J 0
(-7550 350);
DISPLAY 0.680851 (-7550 350);
DISPLAY INVISIBLE (-7550 350);
FORCEPROP 1 LASTPIN (-7700 300) $PN 1
J 0
(-7688 312);
DISPLAY 0.787234 (-7688 312);
PAINT MONO (-7688 312);
FORCEPROP 1 LASTPIN (-7500 300) $PN 2
J 0
(-7538 312);
DISPLAY 0.787234 (-7538 312);
PAINT MONO (-7538 312);
FORCEPROP 1 LAST VALUE 0
J 2
(-7725 300);
DISPLAY 0.489362 (-7725 300);
PAINT SKYBLUE (-7725 300);
FORCEPROP 2 LAST CDS_LIB pure_quanta
J 0
(-7600 300);
DISPLAY INVISIBLE (-7600 300);
FORCEPROP 2 LAST BOM_COST MEM
J 2
(-7575 450);
DISPLAY 0.744681 (-7575 450);
PAINT WHITE (-7575 450);
DISPLAY INVISIBLE (-7575 450);
FORCEPROP 1 LAST WATTAGE 1/16W
J 2
(-7675 225);
DISPLAY 0.489362 (-7675 225);
PAINT SKYBLUE (-7675 225);
DISPLAY INVISIBLE (-7675 225);
FORCEPROP 1 LAST MATERIAL CHIP
J 2
(-7425 275);
DISPLAY 0.489362 (-7425 275);
PAINT SKYBLUE (-7425 275);
DISPLAY INVISIBLE (-7425 275);
FORCEPROP 1 LAST TOLERANCE 5%
J 0
(-7725 275);
DISPLAY 0.489362 (-7725 275);
PAINT SKYBLUE (-7725 275);
DISPLAY INVISIBLE (-7725 275);
FORCEPROP 1 LAST PACK_TYPE 0402LF
J 2
(-7425 225);
DISPLAY 0.489362 (-7425 225);
PAINT SKYBLUE (-7425 225);
DISPLAY INVISIBLE (-7425 225);
FORCEPROP 1 LAST PATH I17
J 0
(-7650 450);
DISPLAY 0.978723 (-7650 450);
PAINT WHITE (-7650 450);
DISPLAY INVISIBLE (-7650 450);
FORCEPROP 1 LAST PART_NUMBER CS00002JB13
J 2
(-7500 350);
DISPLAY 0.489362 (-7500 350);
PAINT SKYBLUE (-7500 350);
DISPLAY INVISIBLE (-7500 350);
FORCEADD Q_RES..1
(-7600 525);
FORCEPROP 1 LAST LOCATION R734
J 0
(-7625 550);
DISPLAY 0.489362 (-7625 550);
PAINT SKYBLUE (-7625 550);
FORCEPROP 0 LAST $SEC 1
J 0
(-7550 550);
DISPLAY 0.680851 (-7550 550);
PAINT MONO (-7550 550);
DISPLAY INVISIBLE (-7550 550);
FORCEPROP 0 LAST CDS_SEC 1
J 0
(-7550 550);
DISPLAY 0.680851 (-7550 550);
DISPLAY INVISIBLE (-7550 550);
FORCEPROP 1 LASTPIN (-7700 525) $PN 1
J 0
(-7688 537);
DISPLAY 0.787234 (-7688 537);
PAINT MONO (-7688 537);
FORCEPROP 1 LASTPIN (-7500 525) $PN 2
J 0
(-7538 537);
DISPLAY 0.787234 (-7538 537);
PAINT MONO (-7538 537);
FORCEPROP 1 LAST VALUE 0
J 2
(-7725 525);
DISPLAY 0.489362 (-7725 525);
PAINT SKYBLUE (-7725 525);
FORCEPROP 2 LAST CDS_LIB pure_quanta
J 0
(-7600 525);
DISPLAY INVISIBLE (-7600 525);
FORCEPROP 2 LAST BOM_COST MEM
J 2
(-7575 675);
DISPLAY 0.744681 (-7575 675);
PAINT WHITE (-7575 675);
DISPLAY INVISIBLE (-7575 675);
FORCEPROP 1 LAST WATTAGE 1/16W
J 2
(-7675 450);
DISPLAY 0.489362 (-7675 450);
PAINT SKYBLUE (-7675 450);
DISPLAY INVISIBLE (-7675 450);
FORCEPROP 1 LAST MATERIAL CHIP
J 2
(-7425 500);
DISPLAY 0.489362 (-7425 500);
PAINT SKYBLUE (-7425 500);
DISPLAY INVISIBLE (-7425 500);
FORCEPROP 1 LAST TOLERANCE 5%
J 0
(-7725 500);
DISPLAY 0.489362 (-7725 500);
PAINT SKYBLUE (-7725 500);
DISPLAY INVISIBLE (-7725 500);
FORCEPROP 1 LAST PACK_TYPE 0402LF
J 2
(-7425 450);
DISPLAY 0.489362 (-7425 450);
PAINT SKYBLUE (-7425 450);
DISPLAY INVISIBLE (-7425 450);
FORCEPROP 1 LAST PATH I19
J 0
(-7650 675);
DISPLAY 0.978723 (-7650 675);
PAINT WHITE (-7650 675);
DISPLAY INVISIBLE (-7650 675);
FORCEPROP 1 LAST PART_NUMBER CS00002JB13
J 2
(-7500 575);
DISPLAY 0.489362 (-7500 575);
PAINT SKYBLUE (-7500 575);
DISPLAY INVISIBLE (-7500 575);
FORCEADD OFFPAGE..1
(-8800 1000);
FORCEPROP 2 LAST $XR0 27 
J 0
(-9051 1000);
DISPLAY 0.638298 (-9051 1000);
PAINT MONO (-9051 1000);
FORCEPROP 2 LAST CDS_LIB standard
J 0
(-8800 1000);
DISPLAY INVISIBLE (-8800 1000);
FORCEPROP 1 LAST OFFPAGE TRUE
J 0
(-8475 875);
DISPLAY 0.872340 (-8475 875);
PAINT GREEN (-8475 875);
DISPLAY INVISIBLE (-8475 875);
FORCEPROP 1 LAST COMMENT_BODY TRUE
J 0
(-8675 900);
DISPLAY 0.872340 (-8675 900);
PAINT GREEN (-8675 900);
DISPLAY INVISIBLE (-8675 900);
FORCEPROP 2 LAST PATH I2
J 0
(-9000 1050);
DISPLAY 0.680851 (-9000 1050);
DISPLAY INVISIBLE (-9000 1050);
FORCEADD OFFPAGE..2
(-6500 850);
FORCEPROP 2 LAST $XR1 81 
J 0
(-6191 850);
DISPLAY 0.638298 (-6191 850);
PAINT MONO (-6191 850);
FORCEPROP 2 LAST $XR0 167 
J 0
(-6311 850);
DISPLAY 0.638298 (-6311 850);
PAINT MONO (-6311 850);
FORCEPROP 2 LAST CDS_LIB standard
J 0
(-6500 850);
DISPLAY INVISIBLE (-6500 850);
FORCEPROP 1 LAST OFFPAGE TRUE
J 0
(-6175 725);
DISPLAY 0.872340 (-6175 725);
PAINT GREEN (-6175 725);
DISPLAY INVISIBLE (-6175 725);
FORCEPROP 1 LAST COMMENT_BODY TRUE
J 0
(-6545 755);
DISPLAY 0.872340 (-6545 755);
PAINT GREEN (-6545 755);
DISPLAY INVISIBLE (-6545 755);
FORCEPROP 2 LAST PATH I20
J 0
(-6325 925);
DISPLAY 0.680851 (-6325 925);
DISPLAY INVISIBLE (-6325 925);
FORCEADD OFFPAGE..2
(-6500 900);
FORCEPROP 2 LAST $XR1 28 
J 0
(-6191 900);
DISPLAY 0.638298 (-6191 900);
PAINT MONO (-6191 900);
FORCEPROP 2 LAST $XR0 167 
J 0
(-6311 900);
DISPLAY 0.638298 (-6311 900);
PAINT MONO (-6311 900);
FORCEPROP 2 LAST CDS_LIB standard
J 0
(-6500 900);
DISPLAY INVISIBLE (-6500 900);
FORCEPROP 1 LAST OFFPAGE TRUE
J 0
(-6175 775);
DISPLAY 0.872340 (-6175 775);
PAINT GREEN (-6175 775);
DISPLAY INVISIBLE (-6175 775);
FORCEPROP 1 LAST COMMENT_BODY TRUE
J 0
(-6545 805);
DISPLAY 0.872340 (-6545 805);
PAINT GREEN (-6545 805);
DISPLAY INVISIBLE (-6545 805);
FORCEPROP 2 LAST PATH I21
J 0
(-6175 950);
DISPLAY 0.680851 (-6175 950);
DISPLAY INVISIBLE (-6175 950);
FORCEADD OFFPAGE..2
(-6500 950);
FORCEPROP 2 LAST $XR1 82 
J 0
(-6191 950);
DISPLAY 0.638298 (-6191 950);
PAINT MONO (-6191 950);
FORCEPROP 2 LAST $XR0 167 
J 0
(-6311 950);
DISPLAY 0.638298 (-6311 950);
PAINT MONO (-6311 950);
FORCEPROP 2 LAST CDS_LIB standard
J 0
(-6500 950);
DISPLAY INVISIBLE (-6500 950);
FORCEPROP 1 LAST OFFPAGE TRUE
J 0
(-6175 825);
DISPLAY 0.872340 (-6175 825);
PAINT GREEN (-6175 825);
DISPLAY INVISIBLE (-6175 825);
FORCEPROP 1 LAST COMMENT_BODY TRUE
J 0
(-6545 855);
DISPLAY 0.872340 (-6545 855);
PAINT GREEN (-6545 855);
DISPLAY INVISIBLE (-6545 855);
FORCEPROP 2 LAST PATH I22
J 0
(-6175 1000);
DISPLAY 0.680851 (-6175 1000);
DISPLAY INVISIBLE (-6175 1000);
FORCEADD OFFPAGE..2
(-6500 1000);
FORCEPROP 2 LAST $XR1 82 
J 0
(-6191 1000);
DISPLAY 0.638298 (-6191 1000);
PAINT MONO (-6191 1000);
FORCEPROP 2 LAST $XR0 167 
J 0
(-6311 1000);
DISPLAY 0.638298 (-6311 1000);
PAINT MONO (-6311 1000);
FORCEPROP 2 LAST CDS_LIB standard
J 0
(-6500 1000);
DISPLAY INVISIBLE (-6500 1000);
FORCEPROP 1 LAST OFFPAGE TRUE
J 0
(-6175 875);
DISPLAY 0.872340 (-6175 875);
PAINT GREEN (-6175 875);
DISPLAY INVISIBLE (-6175 875);
FORCEPROP 1 LAST COMMENT_BODY TRUE
J 0
(-6545 905);
DISPLAY 0.872340 (-6545 905);
PAINT GREEN (-6545 905);
DISPLAY INVISIBLE (-6545 905);
FORCEPROP 2 LAST PATH I23
J 0
(-6175 1050);
DISPLAY 0.680851 (-6175 1050);
DISPLAY INVISIBLE (-6175 1050);
FORCEADD OFFPAGE..2
(-6500 1050);
FORCEPROP 2 LAST $XR3 165 
J 0
(-6011 1050);
DISPLAY 0.638298 (-6011 1050);
PAINT MONO (-6011 1050);
FORCEPROP 2 LAST $XR2 28 
J 0
(-6101 1050);
DISPLAY 0.638298 (-6101 1050);
PAINT MONO (-6101 1050);
FORCEPROP 2 LAST $XR1 167 
J 0
(-6221 1050);
DISPLAY 0.638298 (-6221 1050);
PAINT MONO (-6221 1050);
FORCEPROP 2 LAST $XR0 81 
J 0
(-6311 1050);
DISPLAY 0.638298 (-6311 1050);
PAINT MONO (-6311 1050);
FORCEPROP 2 LAST CDS_LIB standard
J 0
(-6500 1050);
DISPLAY INVISIBLE (-6500 1050);
FORCEPROP 1 LAST OFFPAGE TRUE
J 0
(-6175 925);
DISPLAY 0.872340 (-6175 925);
PAINT GREEN (-6175 925);
DISPLAY INVISIBLE (-6175 925);
FORCEPROP 1 LAST COMMENT_BODY TRUE
J 0
(-6545 955);
DISPLAY 0.872340 (-6545 955);
PAINT GREEN (-6545 955);
DISPLAY INVISIBLE (-6545 955);
FORCEPROP 2 LAST PATH I24
J 0
(-6000 1100);
DISPLAY 0.680851 (-6000 1100);
DISPLAY INVISIBLE (-6000 1100);
FORCEADD OFFPAGE..2
(-6500 1100);
FORCEPROP 2 LAST $XR1 81 
J 0
(-6191 1100);
DISPLAY 0.638298 (-6191 1100);
PAINT MONO (-6191 1100);
FORCEPROP 2 LAST $XR0 167 
J 0
(-6311 1100);
DISPLAY 0.638298 (-6311 1100);
PAINT MONO (-6311 1100);
FORCEPROP 2 LAST CDS_LIB standard
J 0
(-6500 1100);
DISPLAY INVISIBLE (-6500 1100);
FORCEPROP 1 LAST OFFPAGE TRUE
J 0
(-6175 975);
DISPLAY 0.872340 (-6175 975);
PAINT GREEN (-6175 975);
DISPLAY INVISIBLE (-6175 975);
FORCEPROP 1 LAST COMMENT_BODY TRUE
J 0
(-6545 1005);
DISPLAY 0.872340 (-6545 1005);
PAINT GREEN (-6545 1005);
DISPLAY INVISIBLE (-6545 1005);
FORCEPROP 2 LAST PATH I25
J 0
(-6175 1150);
DISPLAY 0.680851 (-6175 1150);
DISPLAY INVISIBLE (-6175 1150);
FORCEADD OFFPAGE..2
(-6500 1200);
FORCEPROP 2 LAST $XR1 81 
J 0
(-6191 1200);
DISPLAY 0.638298 (-6191 1200);
PAINT MONO (-6191 1200);
FORCEPROP 2 LAST $XR0 167 
J 0
(-6311 1200);
DISPLAY 0.638298 (-6311 1200);
PAINT MONO (-6311 1200);
FORCEPROP 2 LAST CDS_LIB standard
J 0
(-6500 1200);
DISPLAY INVISIBLE (-6500 1200);
FORCEPROP 1 LAST OFFPAGE TRUE
J 0
(-6175 1075);
DISPLAY 0.872340 (-6175 1075);
PAINT GREEN (-6175 1075);
DISPLAY INVISIBLE (-6175 1075);
FORCEPROP 1 LAST COMMENT_BODY TRUE
J 0
(-6545 1105);
DISPLAY 0.872340 (-6545 1105);
PAINT GREEN (-6545 1105);
DISPLAY INVISIBLE (-6545 1105);
FORCEPROP 2 LAST PATH I26
J 0
(-6175 1250);
DISPLAY 0.680851 (-6175 1250);
DISPLAY INVISIBLE (-6175 1250);
FORCEADD OFFPAGE..2
(-6500 1150);
FORCEPROP 2 LAST $XR2 81 
J 0
(-6101 1150);
DISPLAY 0.638298 (-6101 1150);
PAINT MONO (-6101 1150);
FORCEPROP 2 LAST $XR1 27 
J 0
(-6191 1150);
DISPLAY 0.638298 (-6191 1150);
PAINT MONO (-6191 1150);
FORCEPROP 2 LAST $XR0 167 
J 0
(-6311 1150);
DISPLAY 0.638298 (-6311 1150);
PAINT MONO (-6311 1150);
FORCEPROP 2 LAST CDS_LIB standard
J 0
(-6500 1150);
DISPLAY INVISIBLE (-6500 1150);
FORCEPROP 1 LAST OFFPAGE TRUE
J 0
(-6175 1025);
DISPLAY 0.872340 (-6175 1025);
PAINT GREEN (-6175 1025);
DISPLAY INVISIBLE (-6175 1025);
FORCEPROP 1 LAST COMMENT_BODY TRUE
J 0
(-6545 1055);
DISPLAY 0.872340 (-6545 1055);
PAINT GREEN (-6545 1055);
DISPLAY INVISIBLE (-6545 1055);
FORCEPROP 2 LAST PATH I27
J 0
(-6100 1200);
DISPLAY 0.680851 (-6100 1200);
DISPLAY INVISIBLE (-6100 1200);
FORCEADD OFFPAGE..2
(-6500 1250);
FORCEPROP 2 LAST $XR1 81 
J 0
(-6191 1250);
DISPLAY 0.638298 (-6191 1250);
PAINT MONO (-6191 1250);
FORCEPROP 2 LAST $XR0 167 
J 0
(-6311 1250);
DISPLAY 0.638298 (-6311 1250);
PAINT MONO (-6311 1250);
FORCEPROP 2 LAST CDS_LIB standard
J 0
(-6500 1250);
DISPLAY INVISIBLE (-6500 1250);
FORCEPROP 1 LAST OFFPAGE TRUE
J 0
(-6175 1125);
DISPLAY 0.872340 (-6175 1125);
PAINT GREEN (-6175 1125);
DISPLAY INVISIBLE (-6175 1125);
FORCEPROP 1 LAST COMMENT_BODY TRUE
J 0
(-6545 1155);
DISPLAY 0.872340 (-6545 1155);
PAINT GREEN (-6545 1155);
DISPLAY INVISIBLE (-6545 1155);
FORCEPROP 2 LAST PATH I28
J 0
(-6175 1300);
DISPLAY 0.680851 (-6175 1300);
DISPLAY INVISIBLE (-6175 1300);
FORCEADD OFFPAGE..2
(-6500 1300);
FORCEPROP 2 LAST $XR1 81 
J 0
(-6191 1300);
DISPLAY 0.638298 (-6191 1300);
PAINT MONO (-6191 1300);
FORCEPROP 2 LAST $XR0 167 
J 0
(-6311 1300);
DISPLAY 0.638298 (-6311 1300);
PAINT MONO (-6311 1300);
FORCEPROP 2 LAST CDS_LIB standard
J 0
(-6500 1300);
DISPLAY INVISIBLE (-6500 1300);
FORCEPROP 1 LAST OFFPAGE TRUE
J 0
(-6175 1175);
DISPLAY 0.872340 (-6175 1175);
PAINT GREEN (-6175 1175);
DISPLAY INVISIBLE (-6175 1175);
FORCEPROP 1 LAST COMMENT_BODY TRUE
J 0
(-6545 1205);
DISPLAY 0.872340 (-6545 1205);
PAINT GREEN (-6545 1205);
DISPLAY INVISIBLE (-6545 1205);
FORCEPROP 2 LAST PATH I29
J 0
(-6175 1350);
DISPLAY 0.680851 (-6175 1350);
DISPLAY INVISIBLE (-6175 1350);
FORCEADD OFFPAGE..1
(-8800 950);
FORCEPROP 2 LAST $XR0 54 
J 0
(-9051 950);
DISPLAY 0.638298 (-9051 950);
PAINT MONO (-9051 950);
FORCEPROP 2 LAST CDS_LIB standard
J 0
(-8800 950);
DISPLAY INVISIBLE (-8800 950);
FORCEPROP 1 LAST OFFPAGE TRUE
J 0
(-8475 825);
DISPLAY 0.872340 (-8475 825);
PAINT GREEN (-8475 825);
DISPLAY INVISIBLE (-8475 825);
FORCEPROP 1 LAST COMMENT_BODY TRUE
J 0
(-8675 850);
DISPLAY 0.872340 (-8675 850);
PAINT GREEN (-8675 850);
DISPLAY INVISIBLE (-8675 850);
FORCEPROP 2 LAST PATH I3
J 0
(-9000 1000);
DISPLAY 0.680851 (-9000 1000);
DISPLAY INVISIBLE (-9000 1000);
FORCEADD Q_RES..2
R 2
(-8075 2550);
FORCEPROP 1 LAST LOCATION R1262
J 2
(-8120 2675);
DISPLAY 0.489362 (-8120 2675);
PAINT SKYBLUE (-8120 2675);
FORCEPROP 0 LAST $SEC 1
J 0
(-8100 2725);
DISPLAY 0.680851 (-8100 2725);
PAINT MONO (-8100 2725);
DISPLAY INVISIBLE (-8100 2725);
FORCEPROP 0 LAST CDS_SEC 1
J 0
(-8100 2725);
DISPLAY 0.680851 (-8100 2725);
DISPLAY INVISIBLE (-8100 2725);
FORCEPROP 1 LASTPIN (-8075 2650) $PN 1
J 2
(-8080 2612);
DISPLAY 0.489362 (-8080 2612);
PAINT MONO (-8080 2612);
FORCEPROP 1 LASTPIN (-8075 2450) $PN 2
J 2
(-8080 2460);
DISPLAY 0.489362 (-8080 2460);
PAINT MONO (-8080 2460);
FORCEPROP 1 LAST VALUE 10K
J 2
(-8100 2450);
DISPLAY 0.489362 (-8100 2450);
PAINT SKYBLUE (-8100 2450);
FORCEPROP 1 LAST PACK_TYPE 0402LF
J 2
(-8115 2375);
DISPLAY 0.978723 (-8115 2375);
PAINT SKYBLUE (-8115 2375);
DISPLAY INVISIBLE (-8115 2375);
FORCEPROP 1 LAST TOLERANCE 5%
J 2
(-8120 2575);
DISPLAY 0.978723 (-8120 2575);
PAINT SKYBLUE (-8120 2575);
DISPLAY INVISIBLE (-8120 2575);
FORCEPROP 1 LAST MATERIAL CHIP
J 2
(-8115 2475);
DISPLAY 0.978723 (-8115 2475);
PAINT SKYBLUE (-8115 2475);
DISPLAY INVISIBLE (-8115 2475);
FORCEPROP 1 LAST WATTAGE 1/16W
J 2
(-8115 2525);
DISPLAY 0.978723 (-8115 2525);
PAINT SKYBLUE (-8115 2525);
DISPLAY INVISIBLE (-8115 2525);
FORCEPROP 2 LAST CDS_LIB pure_quanta
J 0
(-8075 2550);
DISPLAY INVISIBLE (-8075 2550);
FORCEPROP 1 LAST PATH I30
J 2
(-8125 2725);
DISPLAY 0.978723 (-8125 2725);
PAINT WHITE (-8125 2725);
DISPLAY INVISIBLE (-8125 2725);
FORCEPROP 1 LAST PART_NUMBER CS31002JB08
J 2
(-8115 2425);
DISPLAY 0.978723 (-8115 2425);
PAINT SKYBLUE (-8115 2425);
DISPLAY INVISIBLE (-8115 2425);
FORCEADD UNIVERSAL_POWER..1
R 2
(-8075 2750);
FORCEPROP 3 LASTPIN (-8075 2700) SIG_NAME P1V8_AUX\g
J 0
(-8065 2710);
DISPLAY 0.659574 (-8065 2710);
PAINT MONO (-8065 2710);
DISPLAY INVISIBLE (-8065 2710);
FORCEPROP 1 LAST HDL_POWER P1V8_AUX
J 1
(-8075 2800);
DISPLAY 0.489362 (-8075 2800);
PAINT GREEN (-8075 2800);
FORCEPROP 2 LAST CDS_LIB pure_quanta_power
J 0
(-8075 2750);
DISPLAY INVISIBLE (-8075 2750);
FORCEPROP 1 LAST PATH I31
J 2
(-8125 2775);
DISPLAY 0.872340 (-8125 2775);
PAINT AQUA (-8125 2775);
DISPLAY INVISIBLE (-8125 2775);
FORCEADD UNIVERSAL_GND..1
R 2
(-7950 3425);
FORCEPROP 3 LASTPIN (-7950 3475) SIG_NAME GND\g
J 0
(-7940 3485);
DISPLAY 0.659574 (-7940 3485);
PAINT MONO (-7940 3485);
DISPLAY INVISIBLE (-7940 3485);
FORCEPROP 2 LAST CDS_LIB pure_quanta_power
J 0
(-7950 3425);
DISPLAY INVISIBLE (-7950 3425);
FORCEPROP 1 LAST HDL_POWER GND
J 1
(-7975 3350);
DISPLAY 0.872340 (-7975 3350);
PAINT GREEN (-7975 3350);
DISPLAY INVISIBLE (-7975 3350);
FORCEPROP 1 LAST PATH I32
J 2
(-8025 3425);
DISPLAY 0.872340 (-8025 3425);
PAINT AQUA (-8025 3425);
DISPLAY INVISIBLE (-8025 3425);
FORCEADD Q_RES..2
R 2
(-7950 3625);
FORCEPROP 1 LAST LOCATION R6044
J 2
(-7975 3700);
DISPLAY 0.489362 (-7975 3700);
PAINT SKYBLUE (-7975 3700);
FORCEPROP 0 LAST $SEC 1
J 0
(-7950 3750);
DISPLAY 0.680851 (-7950 3750);
PAINT MONO (-7950 3750);
DISPLAY INVISIBLE (-7950 3750);
FORCEPROP 0 LAST CDS_SEC 1
J 0
(-7950 3750);
DISPLAY 0.680851 (-7950 3750);
DISPLAY INVISIBLE (-7950 3750);
FORCEPROP 1 LASTPIN (-7950 3725) $PN 1
J 2
(-7955 3687);
DISPLAY 0.489362 (-7955 3687);
PAINT MONO (-7955 3687);
FORCEPROP 1 LASTPIN (-7950 3525) $PN 2
J 2
(-7955 3535);
DISPLAY 0.489362 (-7955 3535);
PAINT MONO (-7955 3535);
FORCEPROP 1 LAST VALUE 10K
J 2
(-7975 3525);
DISPLAY 0.489362 (-7975 3525);
PAINT SKYBLUE (-7975 3525);
FORCEPROP 1 LAST PACK_TYPE 0402LF
J 2
(-7990 3450);
DISPLAY 0.978723 (-7990 3450);
PAINT SKYBLUE (-7990 3450);
DISPLAY INVISIBLE (-7990 3450);
FORCEPROP 1 LAST TOLERANCE 5%
J 2
(-7995 3650);
DISPLAY 0.978723 (-7995 3650);
PAINT SKYBLUE (-7995 3650);
DISPLAY INVISIBLE (-7995 3650);
FORCEPROP 1 LAST MATERIAL CHIP
J 2
(-7990 3550);
DISPLAY 0.978723 (-7990 3550);
PAINT SKYBLUE (-7990 3550);
DISPLAY INVISIBLE (-7990 3550);
FORCEPROP 1 LAST WATTAGE 1/16W
J 2
(-7990 3600);
DISPLAY 0.978723 (-7990 3600);
PAINT SKYBLUE (-7990 3600);
DISPLAY INVISIBLE (-7990 3600);
FORCEPROP 2 LAST CDS_LIB pure_quanta
J 0
(-7950 3625);
DISPLAY INVISIBLE (-7950 3625);
FORCEPROP 1 LAST PATH I33
J 2
(-8000 3800);
DISPLAY 0.978723 (-8000 3800);
PAINT WHITE (-8000 3800);
DISPLAY INVISIBLE (-8000 3800);
FORCEPROP 1 LAST PART_NUMBER CS31002JB08
J 2
(-7990 3500);
DISPLAY 0.978723 (-7990 3500);
PAINT SKYBLUE (-7990 3500);
DISPLAY INVISIBLE (-7990 3500);
FORCEADD Q_RES..2
R 2
(-7950 4100);
FORCEPROP 1 LAST LOCATION R5071
J 2
(-7995 4225);
DISPLAY 0.489362 (-7995 4225);
PAINT SKYBLUE (-7995 4225);
FORCEPROP 0 LAST $SEC 1
J 0
(-7975 4275);
DISPLAY 0.680851 (-7975 4275);
PAINT MONO (-7975 4275);
DISPLAY INVISIBLE (-7975 4275);
FORCEPROP 0 LAST CDS_SEC 1
J 0
(-7975 4275);
DISPLAY 0.680851 (-7975 4275);
DISPLAY INVISIBLE (-7975 4275);
FORCEPROP 1 LASTPIN (-7950 4200) $PN 1
J 2
(-7955 4162);
DISPLAY 0.489362 (-7955 4162);
PAINT MONO (-7955 4162);
FORCEPROP 1 LASTPIN (-7950 4000) $PN 2
J 2
(-7955 4010);
DISPLAY 0.489362 (-7955 4010);
PAINT MONO (-7955 4010);
FORCEPROP 1 LAST VALUE 100
J 2
(-7975 4000);
DISPLAY 0.489362 (-7975 4000);
PAINT SKYBLUE (-7975 4000);
FORCEPROP 1 LAST PACK_TYPE 0402LF
J 2
(-7990 3925);
DISPLAY 0.978723 (-7990 3925);
PAINT SKYBLUE (-7990 3925);
DISPLAY INVISIBLE (-7990 3925);
FORCEPROP 1 LAST MATERIAL CHIP
J 2
(-7990 4025);
DISPLAY 0.978723 (-7990 4025);
PAINT SKYBLUE (-7990 4025);
DISPLAY INVISIBLE (-7990 4025);
FORCEPROP 1 LAST WATTAGE 1/16W
J 2
(-7990 4075);
DISPLAY 0.978723 (-7990 4075);
PAINT SKYBLUE (-7990 4075);
DISPLAY INVISIBLE (-7990 4075);
FORCEPROP 2 LAST CDS_LIB pure_quanta
J 0
(-7950 4100);
DISPLAY INVISIBLE (-7950 4100);
FORCEPROP 1 LAST TOLERANCE 1%
J 2
(-7995 4125);
DISPLAY 0.978723 (-7995 4125);
PAINT SKYBLUE (-7995 4125);
DISPLAY INVISIBLE (-7995 4125);
FORCEPROP 1 LAST PATH I34
J 2
(-8000 4275);
DISPLAY 0.978723 (-8000 4275);
PAINT WHITE (-8000 4275);
DISPLAY INVISIBLE (-8000 4275);
FORCEPROP 1 LAST PART_NUMBER CS11002FB07
J 2
(-7990 3975);
DISPLAY 0.978723 (-7990 3975);
PAINT SKYBLUE (-7990 3975);
DISPLAY INVISIBLE (-7990 3975);
FORCEADD OFFPAGE..1
(-5650 700);
FORCEPROP 2 LAST $XR1 167 
J 0
(-6021 700);
DISPLAY 0.638298 (-6021 700);
PAINT MONO (-6021 700);
FORCEPROP 2 LAST $XR0 81 
J 0
(-5901 700);
DISPLAY 0.638298 (-5901 700);
PAINT MONO (-5901 700);
FORCEPROP 2 LAST CDS_LIB standard
J 0
(-5650 700);
DISPLAY INVISIBLE (-5650 700);
FORCEPROP 1 LAST OFFPAGE TRUE
J 0
(-5325 575);
DISPLAY 0.872340 (-5325 575);
DISPLAY INVISIBLE (-5325 575);
FORCEPROP 1 LAST COMMENT_BODY TRUE
J 0
(-5525 600);
DISPLAY 0.872340 (-5525 600);
PAINT GREEN (-5525 600);
DISPLAY INVISIBLE (-5525 600);
FORCEPROP 2 LAST PATH I35
J 0
(-5600 775);
DISPLAY 0.680851 (-5600 775);
DISPLAY INVISIBLE (-5600 775);
FORCEADD UNIVERSAL_GND..1
(-4875 800);
FORCEPROP 3 LASTPIN (-4875 850) SIG_NAME GND\g
J 0
(-4865 860);
DISPLAY 0.659574 (-4865 860);
PAINT MONO (-4865 860);
DISPLAY INVISIBLE (-4865 860);
FORCEPROP 2 LAST CDS_LIB pure_quanta_power
J 0
(-4875 800);
DISPLAY INVISIBLE (-4875 800);
FORCEPROP 1 LAST HDL_POWER GND
J 1
(-4850 725);
DISPLAY 0.872340 (-4850 725);
PAINT GREEN (-4850 725);
DISPLAY INVISIBLE (-4850 725);
FORCEPROP 1 LAST PATH I36
J 0
(-4800 800);
DISPLAY 0.872340 (-4800 800);
PAINT AQUA (-4800 800);
DISPLAY INVISIBLE (-4800 800);
FORCEADD UNIVERSAL_GND..1
(-4750 500);
FORCEPROP 3 LASTPIN (-4750 550) SIG_NAME GND\g
J 0
(-4740 560);
DISPLAY 0.659574 (-4740 560);
PAINT MONO (-4740 560);
DISPLAY INVISIBLE (-4740 560);
FORCEPROP 2 LAST CDS_LIB pure_quanta_power
J 0
(-4750 500);
DISPLAY INVISIBLE (-4750 500);
FORCEPROP 1 LAST HDL_POWER GND
J 1
(-4725 425);
DISPLAY 0.872340 (-4725 425);
PAINT GREEN (-4725 425);
DISPLAY INVISIBLE (-4725 425);
FORCEPROP 1 LAST PATH I37
J 0
(-4675 500);
DISPLAY 0.872340 (-4675 500);
PAINT AQUA (-4675 500);
DISPLAY INVISIBLE (-4675 500);
FORCEADD SN74LVC1G07DBVR..1
(-4475 700);
FORCEPROP 1 LAST LOCATION U124
J 0
(-4525 850);
DISPLAY 0.574468 (-4525 850);
PAINT SKYBLUE (-4525 850);
FORCEPROP 0 LAST $SEC 1
J 0
(-4600 1050);
DISPLAY 0.680851 (-4600 1050);
PAINT MONO (-4600 1050);
DISPLAY INVISIBLE (-4600 1050);
FORCEPROP 0 LAST CDS_SEC 1
J 0
(-4600 1050);
DISPLAY 0.680851 (-4600 1050);
DISPLAY INVISIBLE (-4600 1050);
FORCEPROP 0 LASTPIN (-4650 700) $PN 2
J 2
(-4660 710);
DISPLAY 0.680851 (-4660 710);
PAINT MONO (-4660 710);
FORCEPROP 0 LASTPIN (-4650 600) $PN 3
J 2
(-4660 610);
DISPLAY 0.680851 (-4660 610);
PAINT MONO (-4660 610);
FORCEPROP 0 LASTPIN (-4300 600) $PN 1
J 0
(-4290 610);
DISPLAY 0.680851 (-4290 610);
PAINT MONO (-4290 610);
FORCEPROP 0 LASTPIN (-4650 800) $PN 5
J 2
(-4660 810);
DISPLAY 0.680851 (-4660 810);
PAINT MONO (-4660 810);
FORCEPROP 0 LASTPIN (-4300 700) $PN 4
J 0
(-4290 710);
DISPLAY 0.680851 (-4290 710);
PAINT MONO (-4290 710);
FORCEPROP 1 LAST MATERIAL IC
J 0
(-4600 860);
DISPLAY 0.468085 (-4600 860);
PAINT SKYBLUE (-4600 860);
FORCEPROP 2 LAST PACK_TYPE SMLF
J 0
(-4600 1000);
DISPLAY 0.680851 (-4600 1000);
FORCEPROP 2 LAST VALUE SN74LVC1G07DBVR
J 0
(-4600 950);
DISPLAY 0.446809 (-4600 950);
PAINT SKYBLUE (-4600 950);
FORCEPROP 1 LAST NEEDS_NO_SIZE TRUE
J 0
(-4475 700);
DISPLAY 0.468085 (-4475 700);
PAINT GREEN (-4475 700);
DISPLAY INVISIBLE (-4475 700);
FORCEPROP 2 LAST CDS_LIB pure_quanta
J 0
(-4475 700);
DISPLAY INVISIBLE (-4475 700);
FORCEPROP 1 LAST PATH I38
J 0
(-4375 855);
DISPLAY 0.723404 (-4375 855);
PAINT GREEN (-4375 855);
DISPLAY INVISIBLE (-4375 855);
FORCEPROP 1 LAST PART_NUMBER AL1G0007024
J 0
(-4600 910);
DISPLAY 0.468085 (-4600 910);
PAINT SKYBLUE (-4600 910);
DISPLAY INVISIBLE (-4600 910);
FORCEADD Q_CAP..1
(-4875 1075);
FORCEPROP 1 LAST LOCATION C693
J 0
(-5025 1150);
DISPLAY 0.638298 (-5025 1150);
PAINT SKYBLUE (-5025 1150);
FORCEPROP 0 LAST $SEC 1
J 0
(-5025 1200);
DISPLAY 0.680851 (-5025 1200);
PAINT MONO (-5025 1200);
DISPLAY INVISIBLE (-5025 1200);
FORCEPROP 0 LAST CDS_SEC 1
J 0
(-5025 1200);
DISPLAY 0.680851 (-5025 1200);
DISPLAY INVISIBLE (-5025 1200);
FORCEPROP 1 LASTPIN (-4875 1175) $PN 1
J 0
(-4865 1155);
DISPLAY 0.787234 (-4865 1155);
PAINT MONO (-4865 1155);
FORCEPROP 1 LASTPIN (-4875 975) $PN 2
J 0
(-4865 955);
DISPLAY 0.787234 (-4865 955);
PAINT MONO (-4865 955);
FORCEPROP 1 LAST PACK_TYPE 0402
J 0
(-5025 900);
DISPLAY 0.510638 (-5025 900);
PAINT SKYBLUE (-5025 900);
FORCEPROP 1 LAST MATERIAL X7R
J 0
(-5025 1000);
DISPLAY 0.510638 (-5025 1000);
PAINT SKYBLUE (-5025 1000);
FORCEPROP 1 LAST VOLTAGE 25V
J 0
(-5025 1050);
DISPLAY 0.510638 (-5025 1050);
PAINT SKYBLUE (-5025 1050);
FORCEPROP 1 LAST VALUE 0.1UF
J 0
(-5025 1100);
DISPLAY 0.510638 (-5025 1100);
PAINT SKYBLUE (-5025 1100);
FORCEPROP 2 LAST CDS_LIB pure_quanta
J 0
(-4875 1075);
DISPLAY INVISIBLE (-4875 1075);
FORCEPROP 1 LAST TOLERANCE 10%
J 0
(-4825 1025);
DISPLAY 0.638298 (-4825 1025);
PAINT SKYBLUE (-4825 1025);
DISPLAY INVISIBLE (-4825 1025);
FORCEPROP 1 LAST PATH I39
J 0
(-4825 1225);
DISPLAY 0.978723 (-4825 1225);
PAINT WHITE (-4825 1225);
DISPLAY INVISIBLE (-4825 1225);
FORCEPROP 1 LAST PART_NUMBER CH4104K1B00
J 0
(-5175 950);
DISPLAY 0.510638 (-5175 950);
PAINT SKYBLUE (-5175 950);
DISPLAY INVISIBLE (-5175 950);
FORCEADD UNIVERSAL_GND..1
R 5
(-8325 900);
FORCEPROP 3 LASTPIN (-8275 900) SIG_NAME GND\g
J 0
(-8265 910);
DISPLAY 0.659574 (-8265 910);
PAINT MONO (-8265 910);
DISPLAY INVISIBLE (-8265 910);
FORCEPROP 2 LAST CDS_LIB pure_quanta_power
J 0
(-8325 900);
DISPLAY INVISIBLE (-8325 900);
FORCEPROP 1 LAST HDL_POWER GND
R 3
J 1
(-8400 875);
DISPLAY 0.872340 (-8400 875);
PAINT GREEN (-8400 875);
DISPLAY INVISIBLE (-8400 875);
FORCEPROP 1 LAST PATH I4
R 3
J 0
(-8325 825);
DISPLAY 0.872340 (-8325 825);
PAINT AQUA (-8325 825);
DISPLAY INVISIBLE (-8325 825);
FORCEADD UNIVERSAL_POWER..1
R 2
(-4750 1825);
FORCEPROP 3 LASTPIN (-4750 1775) SIG_NAME P3V3_AUX\g
J 0
(-4740 1785);
DISPLAY 0.659574 (-4740 1785);
PAINT MONO (-4740 1785);
DISPLAY INVISIBLE (-4740 1785);
FORCEPROP 1 LAST HDL_POWER P3V3_AUX
J 1
(-4750 1875);
DISPLAY 0.489362 (-4750 1875);
PAINT GREEN (-4750 1875);
FORCEPROP 2 LAST CDS_LIB pure_quanta_power
J 0
(-4750 1825);
DISPLAY INVISIBLE (-4750 1825);
FORCEPROP 1 LAST PATH I40
J 2
(-4800 1850);
DISPLAY 0.872340 (-4800 1850);
PAINT AQUA (-4800 1850);
DISPLAY INVISIBLE (-4800 1850);
FORCEADD OFFPAGE..5
(-5775 2250);
FORCEPROP 2 LAST $XR3 165 
J 0
(-6329 2250);
DISPLAY 0.638298 (-6329 2250);
PAINT MONO (-6329 2250);
FORCEPROP 2 LAST $XR2 28 
J 0
(-6209 2250);
DISPLAY 0.638298 (-6209 2250);
PAINT MONO (-6209 2250);
FORCEPROP 2 LAST $XR1 167 
J 0
(-6119 2250);
DISPLAY 0.638298 (-6119 2250);
PAINT MONO (-6119 2250);
FORCEPROP 2 LAST $XR0 81 
J 0
(-5999 2250);
DISPLAY 0.638298 (-5999 2250);
PAINT MONO (-5999 2250);
FORCEPROP 2 LAST CDS_LIB standard
J 0
(-5775 2250);
DISPLAY INVISIBLE (-5775 2250);
FORCEPROP 1 LAST OFFPAGE TRUE
J 0
(-5450 2125);
DISPLAY 0.872340 (-5450 2125);
PAINT GREEN (-5450 2125);
DISPLAY INVISIBLE (-5450 2125);
FORCEPROP 1 LAST COMMENT_BODY TRUE
J 0
(-5675 2175);
DISPLAY 0.872340 (-5675 2175);
PAINT GREEN (-5675 2175);
DISPLAY INVISIBLE (-5675 2175);
FORCEPROP 2 LAST PATH I41
J 0
(-5975 2300);
DISPLAY 0.680851 (-5975 2300);
DISPLAY INVISIBLE (-5975 2300);
FORCEADD OFFPAGE..5
(-5675 4000);
FORCEPROP 2 LAST $XR1 172 
J 0
(-6050 4000);
DISPLAY 0.638298 (-6050 4000);
PAINT MONO (-6050 4000);
FORCEPROP 2 LAST $XR0 167 
J 0
(-5930 4000);
DISPLAY 0.638298 (-5930 4000);
PAINT MONO (-5930 4000);
FORCEPROP 2 LAST CDS_LIB standard
J 0
(-5675 4000);
DISPLAY INVISIBLE (-5675 4000);
FORCEPROP 1 LAST OFFPAGE TRUE
J 0
(-5350 3875);
DISPLAY 0.872340 (-5350 3875);
PAINT GREEN (-5350 3875);
DISPLAY INVISIBLE (-5350 3875);
FORCEPROP 1 LAST COMMENT_BODY TRUE
J 0
(-5575 3925);
DISPLAY 0.872340 (-5575 3925);
PAINT GREEN (-5575 3925);
DISPLAY INVISIBLE (-5575 3925);
FORCEPROP 2 LAST PATH I42
J 0
(-5925 4050);
DISPLAY 0.680851 (-5925 4050);
DISPLAY INVISIBLE (-5925 4050);
FORCEADD OFFPAGE..1
(-5675 4050);
FORCEPROP 2 LAST $XR1 167 
J 0
(-6046 4050);
DISPLAY 0.638298 (-6046 4050);
PAINT MONO (-6046 4050);
FORCEPROP 2 LAST $XR0 81 
J 0
(-5926 4050);
DISPLAY 0.638298 (-5926 4050);
PAINT MONO (-5926 4050);
FORCEPROP 2 LAST CDS_LIB standard
J 0
(-5675 4050);
DISPLAY INVISIBLE (-5675 4050);
FORCEPROP 1 LAST OFFPAGE TRUE
J 0
(-5350 3925);
DISPLAY 0.872340 (-5350 3925);
PAINT GREEN (-5350 3925);
DISPLAY INVISIBLE (-5350 3925);
FORCEPROP 1 LAST COMMENT_BODY TRUE
J 0
(-5550 3950);
DISPLAY 0.872340 (-5550 3950);
PAINT GREEN (-5550 3950);
DISPLAY INVISIBLE (-5550 3950);
FORCEPROP 2 LAST PATH I43
J 0
(-5875 4100);
DISPLAY 0.680851 (-5875 4100);
DISPLAY INVISIBLE (-5875 4100);
FORCEADD Q_RES..2
R 2
(-5025 2450);
FORCEPROP 1 LAST LOCATION R1264
J 2
(-5070 2575);
DISPLAY 0.489362 (-5070 2575);
PAINT SKYBLUE (-5070 2575);
FORCEPROP 0 LAST $SEC 1
J 0
(-5050 2625);
DISPLAY 0.680851 (-5050 2625);
PAINT MONO (-5050 2625);
DISPLAY INVISIBLE (-5050 2625);
FORCEPROP 0 LAST CDS_SEC 1
J 0
(-5050 2625);
DISPLAY 0.680851 (-5050 2625);
DISPLAY INVISIBLE (-5050 2625);
FORCEPROP 1 LASTPIN (-5025 2550) $PN 1
J 2
(-5030 2512);
DISPLAY 0.489362 (-5030 2512);
PAINT MONO (-5030 2512);
FORCEPROP 1 LASTPIN (-5025 2350) $PN 2
J 2
(-5030 2360);
DISPLAY 0.489362 (-5030 2360);
PAINT MONO (-5030 2360);
FORCEPROP 1 LAST VALUE 1K
J 2
(-5050 2350);
DISPLAY 0.489362 (-5050 2350);
PAINT SKYBLUE (-5050 2350);
FORCEPROP 1 LAST MATERIAL EMPTY
J 2
(-5065 2375);
DISPLAY 0.978723 (-5065 2375);
PAINT SKYBLUE (-5065 2375);
DISPLAY INVISIBLE (-5065 2375);
FORCEPROP 1 LAST TOLERANCE 1%
J 2
(-5070 2475);
DISPLAY 0.978723 (-5070 2475);
PAINT SKYBLUE (-5070 2475);
DISPLAY INVISIBLE (-5070 2475);
FORCEPROP 1 LAST PACK_TYPE 0402LF
J 2
(-5065 2275);
DISPLAY 0.978723 (-5065 2275);
PAINT SKYBLUE (-5065 2275);
DISPLAY INVISIBLE (-5065 2275);
FORCEPROP 1 LAST WATTAGE 1/16W
J 2
(-5065 2425);
DISPLAY 0.978723 (-5065 2425);
PAINT SKYBLUE (-5065 2425);
DISPLAY INVISIBLE (-5065 2425);
FORCEPROP 2 LAST CDS_LIB pure_quanta
J 0
(-5025 2450);
DISPLAY INVISIBLE (-5025 2450);
FORCEPROP 1 LAST PATH I44
J 2
(-5075 2625);
DISPLAY 0.978723 (-5075 2625);
PAINT WHITE (-5075 2625);
DISPLAY INVISIBLE (-5075 2625);
FORCEPROP 1 LAST PART_NUMBER CS21002FB06
J 2
(-5065 2325);
DISPLAY 0.978723 (-5065 2325);
PAINT SKYBLUE (-5065 2325);
DISPLAY INVISIBLE (-5065 2325);
FORCEADD UNIVERSAL_POWER..1
R 2
(-5025 2650);
FORCEPROP 3 LASTPIN (-5025 2600) SIG_NAME P1V8_AUX\g
J 0
(-5015 2610);
DISPLAY 0.659574 (-5015 2610);
PAINT MONO (-5015 2610);
DISPLAY INVISIBLE (-5015 2610);
FORCEPROP 1 LAST HDL_POWER P1V8_AUX
J 1
(-5025 2700);
DISPLAY 0.489362 (-5025 2700);
PAINT GREEN (-5025 2700);
FORCEPROP 2 LAST CDS_LIB pure_quanta_power
J 0
(-5025 2650);
DISPLAY INVISIBLE (-5025 2650);
FORCEPROP 1 LAST PATH I45
J 2
(-5075 2675);
DISPLAY 0.872340 (-5075 2675);
PAINT AQUA (-5075 2675);
DISPLAY INVISIBLE (-5075 2675);
FORCEADD UNIVERSAL_GND..1
R 2
(-4300 3550);
FORCEPROP 3 LASTPIN (-4300 3600) SIG_NAME GND\g
J 0
(-4290 3610);
DISPLAY 0.659574 (-4290 3610);
PAINT MONO (-4290 3610);
DISPLAY INVISIBLE (-4290 3610);
FORCEPROP 2 LAST CDS_LIB pure_quanta_power
J 0
(-4300 3550);
DISPLAY INVISIBLE (-4300 3550);
FORCEPROP 1 LAST HDL_POWER GND
J 1
(-4325 3475);
DISPLAY 0.872340 (-4325 3475);
PAINT GREEN (-4325 3475);
DISPLAY INVISIBLE (-4325 3475);
FORCEPROP 1 LAST PATH I46
J 2
(-4375 3550);
DISPLAY 0.872340 (-4375 3550);
PAINT AQUA (-4375 3550);
DISPLAY INVISIBLE (-4375 3550);
FORCEADD Q_RES..1
R 1
(-4300 3900);
FORCEPROP 1 LAST LOCATION R8
R 1
J 0
(-4350 3850);
DISPLAY 0.510638 (-4350 3850);
PAINT SKYBLUE (-4350 3850);
FORCEPROP 0 LAST $SEC 1
R 1
J 0
(-4275 4025);
DISPLAY 0.680851 (-4275 4025);
PAINT MONO (-4275 4025);
DISPLAY INVISIBLE (-4275 4025);
FORCEPROP 0 LAST CDS_SEC 1
R 1
J 0
(-4275 4025);
DISPLAY 0.680851 (-4275 4025);
DISPLAY INVISIBLE (-4275 4025);
FORCEPROP 1 LASTPIN (-4300 3800) $PN 1
R 1
J 0
(-4312 3812);
DISPLAY 0.404255 (-4312 3812);
PAINT MONO (-4312 3812);
FORCEPROP 1 LASTPIN (-4300 4000) $PN 2
R 1
J 0
(-4312 3962);
DISPLAY 0.404255 (-4312 3962);
PAINT MONO (-4312 3962);
FORCEPROP 1 LAST MATERIAL CHIP
R 1
J 0
(-4225 3975);
DISPLAY 0.510638 (-4225 3975);
PAINT SKYBLUE (-4225 3975);
FORCEPROP 1 LAST VALUE 100K
R 1
J 2
(-4225 3925);
DISPLAY 0.510638 (-4225 3925);
PAINT SKYBLUE (-4225 3925);
FORCEPROP 2 LAST CDS_LIB pure_quanta
R 1
J 0
(-4300 3900);
DISPLAY INVISIBLE (-4300 3900);
FORCEPROP 1 LAST PACK_TYPE 0402LF
R 1
J 0
(-4150 4150);
DISPLAY 0.978723 (-4150 4150);
DISPLAY INVISIBLE (-4150 4150);
FORCEPROP 1 LAST WATTAGE 1/16W
R 1
J 2
(-4150 3875);
DISPLAY 0.978723 (-4150 3875);
DISPLAY INVISIBLE (-4150 3875);
FORCEPROP 1 LAST TOLERANCE 1%
R 1
J 0
(-4200 3900);
DISPLAY 0.978723 (-4200 3900);
DISPLAY INVISIBLE (-4200 3900);
FORCEPROP 1 LAST PATH I47
R 1
J 0
(-4450 3850);
DISPLAY 0.978723 (-4450 3850);
PAINT WHITE (-4450 3850);
DISPLAY INVISIBLE (-4450 3850);
FORCEPROP 1 LAST PART_NUMBER CS41002FB09
R 1
J 0
(-4400 3850);
DISPLAY 0.978723 (-4400 3850);
DISPLAY INVISIBLE (-4400 3850);
FORCEADD UNIVERSAL_POWER..1
R 2
(-7950 4300);
FORCEPROP 3 LASTPIN (-7950 4250) SIG_NAME P1V8_AUX\g
J 0
(-7940 4260);
DISPLAY 0.659574 (-7940 4260);
PAINT MONO (-7940 4260);
DISPLAY INVISIBLE (-7940 4260);
FORCEPROP 1 LAST HDL_POWER P1V8_AUX
J 1
(-7950 4350);
DISPLAY 0.489362 (-7950 4350);
PAINT GREEN (-7950 4350);
FORCEPROP 2 LAST CDS_LIB pure_quanta_power
J 0
(-7950 4300);
DISPLAY INVISIBLE (-7950 4300);
FORCEPROP 1 LAST PATH I48
J 2
(-8000 4325);
DISPLAY 0.872340 (-8000 4325);
PAINT AQUA (-8000 4325);
DISPLAY INVISIBLE (-8000 4325);
FORCEADD OFFPAGE..5
(-4925 5325);
FORCEPROP 2 LAST $XR2 81 
J 0
(-5390 5325);
DISPLAY 0.638298 (-5390 5325);
PAINT MONO (-5390 5325);
FORCEPROP 2 LAST $XR1 27 
J 0
(-5300 5325);
DISPLAY 0.638298 (-5300 5325);
PAINT MONO (-5300 5325);
FORCEPROP 2 LAST $XR0 167 
J 0
(-5210 5325);
DISPLAY 0.638298 (-5210 5325);
PAINT MONO (-5210 5325);
FORCEPROP 2 LAST CDS_LIB standard
J 0
(-4925 5325);
DISPLAY INVISIBLE (-4925 5325);
FORCEPROP 1 LAST OFFPAGE TRUE
J 0
(-4600 5200);
DISPLAY 0.872340 (-4600 5200);
PAINT GREEN (-4600 5200);
DISPLAY INVISIBLE (-4600 5200);
FORCEPROP 1 LAST COMMENT_BODY TRUE
J 0
(-4825 5250);
DISPLAY 0.872340 (-4825 5250);
PAINT GREEN (-4825 5250);
DISPLAY INVISIBLE (-4825 5250);
FORCEPROP 2 LAST PATH I49
J 0
(-5175 5375);
DISPLAY 0.680851 (-5175 5375);
DISPLAY INVISIBLE (-5175 5375);
FORCEADD UNIVERSAL_GND..1
R 5
(-9125 1050);
FORCEPROP 3 LASTPIN (-9075 1050) SIG_NAME GND\g
J 0
(-9065 1060);
DISPLAY 0.659574 (-9065 1060);
PAINT MONO (-9065 1060);
DISPLAY INVISIBLE (-9065 1060);
FORCEPROP 2 LAST CDS_LIB pure_quanta_power
J 0
(-9125 1050);
DISPLAY INVISIBLE (-9125 1050);
FORCEPROP 1 LAST HDL_POWER GND
R 3
J 1
(-9200 1025);
DISPLAY 0.872340 (-9200 1025);
PAINT GREEN (-9200 1025);
DISPLAY INVISIBLE (-9200 1025);
FORCEPROP 1 LAST PATH I5
R 3
J 0
(-9125 975);
DISPLAY 0.872340 (-9125 975);
PAINT AQUA (-9125 975);
DISPLAY INVISIBLE (-9125 975);
FORCEADD Q_RES..2
(-4800 4250);
FORCEPROP 1 LAST LOCATION R733
J 0
(-4755 4375);
DISPLAY 0.489362 (-4755 4375);
PAINT SKYBLUE (-4755 4375);
FORCEPROP 0 LAST $SEC 1
J 0
(-4750 4425);
DISPLAY 0.680851 (-4750 4425);
PAINT MONO (-4750 4425);
DISPLAY INVISIBLE (-4750 4425);
FORCEPROP 0 LAST CDS_SEC 1
J 0
(-4750 4425);
DISPLAY 0.680851 (-4750 4425);
DISPLAY INVISIBLE (-4750 4425);
FORCEPROP 1 LASTPIN (-4800 4350) $PN 1
J 0
(-4795 4312);
DISPLAY 0.489362 (-4795 4312);
PAINT MONO (-4795 4312);
FORCEPROP 1 LASTPIN (-4800 4150) $PN 2
J 0
(-4795 4160);
DISPLAY 0.489362 (-4795 4160);
PAINT MONO (-4795 4160);
FORCEPROP 1 LAST WATTAGE 1/16W
J 0
(-4760 4225);
DISPLAY 0.489362 (-4760 4225);
PAINT SKYBLUE (-4760 4225);
FORCEPROP 1 LAST MATERIAL EMPTY
J 0
(-4760 4175);
DISPLAY 0.489362 (-4760 4175);
PAINT RED (-4760 4175);
FORCEPROP 1 LAST PACK_TYPE 0402LF
J 0
(-4750 4125);
DISPLAY 0.489362 (-4750 4125);
PAINT SKYBLUE (-4750 4125);
FORCEPROP 1 LAST VALUE 100
J 0
(-4755 4325);
DISPLAY 0.489362 (-4755 4325);
PAINT SKYBLUE (-4755 4325);
FORCEPROP 1 LAST TOLERANCE 1%
J 0
(-4755 4275);
DISPLAY 0.489362 (-4755 4275);
PAINT SKYBLUE (-4755 4275);
FORCEPROP 2 LAST CDS_LIB pure_quanta
J 0
(-4800 4250);
DISPLAY INVISIBLE (-4800 4250);
FORCEPROP 1 LAST PATH I50
J 0
(-4750 4425);
DISPLAY 0.978723 (-4750 4425);
PAINT WHITE (-4750 4425);
DISPLAY INVISIBLE (-4750 4425);
FORCEPROP 1 LAST PART_NUMBER CS11002FB07
J 0
(-4760 4125);
DISPLAY 0.617021 (-4760 4125);
PAINT SKYBLUE (-4760 4125);
DISPLAY INVISIBLE (-4760 4125);
FORCEADD UNIVERSAL_POWER..1
R 2
(-4800 4450);
FORCEPROP 3 LASTPIN (-4800 4400) SIG_NAME P1V8_AUX\g
J 0
(-4790 4410);
DISPLAY 0.659574 (-4790 4410);
PAINT MONO (-4790 4410);
DISPLAY INVISIBLE (-4790 4410);
FORCEPROP 1 LAST HDL_POWER P1V8_AUX
J 1
(-4800 4500);
DISPLAY 0.489362 (-4800 4500);
PAINT GREEN (-4800 4500);
FORCEPROP 2 LAST CDS_LIB pure_quanta_power
J 0
(-4800 4450);
DISPLAY INVISIBLE (-4800 4450);
FORCEPROP 1 LAST PATH I51
J 2
(-4850 4475);
DISPLAY 0.872340 (-4850 4475);
PAINT AQUA (-4850 4475);
DISPLAY INVISIBLE (-4850 4475);
FORCEADD Q_RES..2
R 2
(-4075 5150);
FORCEPROP 1 LAST LOCATION R1265
J 2
(-4075 5225);
DISPLAY 0.489362 (-4075 5225);
PAINT SKYBLUE (-4075 5225);
FORCEPROP 0 LAST $SEC 1
J 0
(-4075 5275);
DISPLAY 0.680851 (-4075 5275);
PAINT MONO (-4075 5275);
DISPLAY INVISIBLE (-4075 5275);
FORCEPROP 0 LAST CDS_SEC 1
J 0
(-4075 5275);
DISPLAY 0.680851 (-4075 5275);
DISPLAY INVISIBLE (-4075 5275);
FORCEPROP 1 LASTPIN (-4075 5250) $PN 1
J 2
(-4080 5212);
DISPLAY 0.489362 (-4080 5212);
PAINT MONO (-4080 5212);
FORCEPROP 1 LASTPIN (-4075 5050) $PN 2
J 2
(-4080 5060);
DISPLAY 0.489362 (-4080 5060);
PAINT MONO (-4080 5060);
FORCEPROP 1 LAST VALUE 10K
J 2
(-4100 5050);
DISPLAY 0.489362 (-4100 5050);
PAINT SKYBLUE (-4100 5050);
FORCEPROP 1 LAST PACK_TYPE 0402LF
J 2
(-4115 4975);
DISPLAY 0.978723 (-4115 4975);
PAINT SKYBLUE (-4115 4975);
DISPLAY INVISIBLE (-4115 4975);
FORCEPROP 1 LAST TOLERANCE 5%
J 2
(-4120 5175);
DISPLAY 0.978723 (-4120 5175);
PAINT SKYBLUE (-4120 5175);
DISPLAY INVISIBLE (-4120 5175);
FORCEPROP 1 LAST MATERIAL CHIP
J 2
(-4115 5075);
DISPLAY 0.978723 (-4115 5075);
PAINT SKYBLUE (-4115 5075);
DISPLAY INVISIBLE (-4115 5075);
FORCEPROP 1 LAST WATTAGE 1/16W
J 2
(-4115 5125);
DISPLAY 0.978723 (-4115 5125);
PAINT SKYBLUE (-4115 5125);
DISPLAY INVISIBLE (-4115 5125);
FORCEPROP 2 LAST CDS_LIB pure_quanta
J 0
(-4075 5150);
DISPLAY INVISIBLE (-4075 5150);
FORCEPROP 1 LAST PATH I52
J 2
(-4125 5325);
DISPLAY 0.978723 (-4125 5325);
PAINT WHITE (-4125 5325);
DISPLAY INVISIBLE (-4125 5325);
FORCEPROP 1 LAST PART_NUMBER CS31002JB08
J 2
(-4115 5025);
DISPLAY 0.978723 (-4115 5025);
PAINT SKYBLUE (-4115 5025);
DISPLAY INVISIBLE (-4115 5025);
FORCEADD UNIVERSAL_GND..1
R 2
(-4075 4950);
FORCEPROP 3 LASTPIN (-4075 5000) SIG_NAME GND\g
J 0
(-4065 5010);
DISPLAY 0.659574 (-4065 5010);
PAINT MONO (-4065 5010);
DISPLAY INVISIBLE (-4065 5010);
FORCEPROP 2 LAST CDS_LIB pure_quanta_power
J 0
(-4075 4950);
DISPLAY INVISIBLE (-4075 4950);
FORCEPROP 1 LAST HDL_POWER GND
J 1
(-4100 4875);
DISPLAY 0.872340 (-4100 4875);
PAINT GREEN (-4100 4875);
DISPLAY INVISIBLE (-4100 4875);
FORCEPROP 1 LAST PATH I53
J 2
(-4150 4950);
DISPLAY 0.872340 (-4150 4950);
PAINT AQUA (-4150 4950);
DISPLAY INVISIBLE (-4150 4950);
FORCEADD Q_RES..2
(-4850 5725);
FORCEPROP 1 LAST LOCATION R22
J 0
(-4805 5850);
DISPLAY 0.489362 (-4805 5850);
PAINT SKYBLUE (-4805 5850);
FORCEPROP 0 LAST $SEC 1
J 0
(-4800 5900);
DISPLAY 0.680851 (-4800 5900);
PAINT MONO (-4800 5900);
DISPLAY INVISIBLE (-4800 5900);
FORCEPROP 0 LAST CDS_SEC 1
J 0
(-4800 5900);
DISPLAY 0.680851 (-4800 5900);
DISPLAY INVISIBLE (-4800 5900);
FORCEPROP 1 LASTPIN (-4850 5825) $PN 1
J 0
(-4845 5787);
DISPLAY 0.489362 (-4845 5787);
PAINT MONO (-4845 5787);
FORCEPROP 1 LASTPIN (-4850 5625) $PN 2
J 0
(-4845 5635);
DISPLAY 0.489362 (-4845 5635);
PAINT MONO (-4845 5635);
FORCEPROP 1 LAST WATTAGE 1/16W
J 0
(-4810 5700);
DISPLAY 0.489362 (-4810 5700);
PAINT SKYBLUE (-4810 5700);
FORCEPROP 1 LAST MATERIAL CHIP
J 0
(-4810 5650);
DISPLAY 0.489362 (-4810 5650);
PAINT SKYBLUE (-4810 5650);
FORCEPROP 1 LAST TOLERANCE 1%
J 0
(-4805 5750);
DISPLAY 0.489362 (-4805 5750);
PAINT SKYBLUE (-4805 5750);
FORCEPROP 1 LAST VALUE 100
J 0
(-4805 5800);
DISPLAY 0.489362 (-4805 5800);
PAINT SKYBLUE (-4805 5800);
FORCEPROP 1 LAST PACK_TYPE 0402LF
J 0
(-4800 5600);
DISPLAY 0.489362 (-4800 5600);
PAINT SKYBLUE (-4800 5600);
FORCEPROP 2 LAST CDS_LIB pure_quanta
J 0
(-4850 5725);
DISPLAY INVISIBLE (-4850 5725);
FORCEPROP 1 LAST PATH I54
J 0
(-4800 5900);
DISPLAY 0.978723 (-4800 5900);
PAINT WHITE (-4800 5900);
DISPLAY INVISIBLE (-4800 5900);
FORCEPROP 1 LAST PART_NUMBER CS11002FB07
J 0
(-4810 5600);
DISPLAY 0.617021 (-4810 5600);
PAINT SKYBLUE (-4810 5600);
DISPLAY INVISIBLE (-4810 5600);
FORCEADD UNIVERSAL_POWER..1
R 2
(-4850 5925);
FORCEPROP 3 LASTPIN (-4850 5875) SIG_NAME P1V8_AUX\g
J 0
(-4840 5885);
DISPLAY 0.659574 (-4840 5885);
PAINT MONO (-4840 5885);
DISPLAY INVISIBLE (-4840 5885);
FORCEPROP 1 LAST HDL_POWER P1V8_AUX
J 1
(-4850 5975);
DISPLAY 0.489362 (-4850 5975);
PAINT GREEN (-4850 5975);
FORCEPROP 2 LAST CDS_LIB pure_quanta_power
J 0
(-4850 5925);
DISPLAY INVISIBLE (-4850 5925);
FORCEPROP 1 LAST PATH I55
J 2
(-4900 5950);
DISPLAY 0.872340 (-4900 5950);
PAINT AQUA (-4900 5950);
DISPLAY INVISIBLE (-4900 5950);
FORCEADD OFFPAGE..2
(-4200 5525);
FORCEPROP 2 LAST $XR0 167 
J 0
(-4011 5525);
DISPLAY 0.638298 (-4011 5525);
PAINT MONO (-4011 5525);
FORCEPROP 2 LAST CDS_LIB standard
J 0
(-4200 5525);
DISPLAY INVISIBLE (-4200 5525);
FORCEPROP 1 LAST OFFPAGE TRUE
J 0
(-3875 5400);
DISPLAY 0.872340 (-3875 5400);
PAINT GREEN (-3875 5400);
DISPLAY INVISIBLE (-3875 5400);
FORCEPROP 1 LAST COMMENT_BODY TRUE
J 0
(-4245 5430);
DISPLAY 0.872340 (-4245 5430);
PAINT GREEN (-4245 5430);
DISPLAY INVISIBLE (-4245 5430);
FORCEPROP 2 LAST PATH I56
J 0
(-4000 5575);
DISPLAY 0.680851 (-4000 5575);
DISPLAY INVISIBLE (-4000 5575);
FORCEADD OFFPAGE..2
(-3675 700);
FORCEPROP 2 LAST $XR1 172 
J 0
(-3366 700);
DISPLAY 0.638298 (-3366 700);
PAINT MONO (-3366 700);
FORCEPROP 2 LAST $XR0 167 
J 0
(-3486 700);
DISPLAY 0.638298 (-3486 700);
PAINT MONO (-3486 700);
FORCEPROP 2 LAST CDS_LIB standard
J 0
(-3675 700);
DISPLAY INVISIBLE (-3675 700);
FORCEPROP 1 LAST OFFPAGE TRUE
J 0
(-3350 575);
DISPLAY 0.872340 (-3350 575);
DISPLAY INVISIBLE (-3350 575);
FORCEPROP 1 LAST COMMENT_BODY TRUE
J 0
(-3720 605);
DISPLAY 0.872340 (-3720 605);
PAINT GREEN (-3720 605);
DISPLAY INVISIBLE (-3720 605);
FORCEPROP 2 LAST PATH I57
J 0
(-3500 775);
DISPLAY 0.680851 (-3500 775);
DISPLAY INVISIBLE (-3500 775);
FORCEADD OFFPAGE..5
(-3200 1350);
FORCEPROP 2 LAST $XR0 167 
J 0
(-3455 1350);
DISPLAY 0.638298 (-3455 1350);
PAINT MONO (-3455 1350);
FORCEPROP 2 LAST CDS_LIB standard
J 0
(-3200 1350);
DISPLAY INVISIBLE (-3200 1350);
FORCEPROP 1 LAST OFFPAGE TRUE
J 0
(-2875 1225);
DISPLAY 0.872340 (-2875 1225);
PAINT GREEN (-2875 1225);
DISPLAY INVISIBLE (-2875 1225);
FORCEPROP 1 LAST COMMENT_BODY TRUE
J 0
(-3100 1275);
DISPLAY 0.872340 (-3100 1275);
PAINT GREEN (-3100 1275);
DISPLAY INVISIBLE (-3100 1275);
FORCEPROP 2 LAST PATH I58
J 0
(-3150 1425);
DISPLAY 0.680851 (-3150 1425);
DISPLAY INVISIBLE (-3150 1425);
FORCEADD OFFPAGE..5
(-3200 1275);
FORCEPROP 2 LAST $XR1 81 
J 0
(-3545 1275);
DISPLAY 0.638298 (-3545 1275);
PAINT MONO (-3545 1275);
FORCEPROP 2 LAST $XR0 167 
J 0
(-3455 1275);
DISPLAY 0.638298 (-3455 1275);
PAINT MONO (-3455 1275);
FORCEPROP 2 LAST CDS_LIB standard
J 0
(-3200 1275);
DISPLAY INVISIBLE (-3200 1275);
FORCEPROP 1 LAST OFFPAGE TRUE
J 0
(-2875 1150);
DISPLAY 0.872340 (-2875 1150);
PAINT GREEN (-2875 1150);
DISPLAY INVISIBLE (-2875 1150);
FORCEPROP 1 LAST COMMENT_BODY TRUE
J 0
(-3100 1200);
DISPLAY 0.872340 (-3100 1200);
PAINT GREEN (-3100 1200);
DISPLAY INVISIBLE (-3100 1200);
FORCEPROP 2 LAST PATH I59
J 0
(-3150 1350);
DISPLAY 0.680851 (-3150 1350);
DISPLAY INVISIBLE (-3150 1350);
FORCEADD Q_RES..1
(-8900 1050);
FORCEPROP 1 LAST LOCATION R1508
J 0
(-9025 1050);
DISPLAY 0.489362 (-9025 1050);
PAINT SKYBLUE (-9025 1050);
FORCEPROP 0 LAST $SEC 1
J 0
(-8800 1075);
DISPLAY 0.680851 (-8800 1075);
PAINT MONO (-8800 1075);
DISPLAY INVISIBLE (-8800 1075);
FORCEPROP 0 LAST CDS_SEC 1
J 0
(-8800 1075);
DISPLAY 0.680851 (-8800 1075);
DISPLAY INVISIBLE (-8800 1075);
FORCEPROP 1 LASTPIN (-9000 1050) $PN 1
J 0
(-8988 1062);
DISPLAY 0.489362 (-8988 1062);
PAINT MONO (-8988 1062);
FORCEPROP 1 LASTPIN (-8800 1050) $PN 2
J 0
(-8838 1062);
DISPLAY 0.489362 (-8838 1062);
PAINT MONO (-8838 1062);
FORCEPROP 1 LAST VALUE 100
J 0
(-8800 1050);
DISPLAY 0.489362 (-8800 1050);
PAINT SKYBLUE (-8800 1050);
FORCEPROP 1 LAST TOLERANCE 1%
J 0
(-8900 950);
DISPLAY 0.978723 (-8900 950);
PAINT SKYBLUE (-8900 950);
DISPLAY INVISIBLE (-8900 950);
FORCEPROP 1 LAST PACK_TYPE 0402LF
J 0
(-8650 900);
DISPLAY 0.978723 (-8650 900);
PAINT SKYBLUE (-8650 900);
DISPLAY INVISIBLE (-8650 900);
FORCEPROP 1 LAST MATERIAL CHIP
J 0
(-8900 900);
DISPLAY 0.978723 (-8900 900);
PAINT SKYBLUE (-8900 900);
DISPLAY INVISIBLE (-8900 900);
FORCEPROP 1 LAST WATTAGE 1/16W
J 2
(-8925 900);
DISPLAY 0.978723 (-8925 900);
PAINT SKYBLUE (-8925 900);
DISPLAY INVISIBLE (-8925 900);
FORCEPROP 2 LAST CDS_LIB pure_quanta
J 0
(-8900 1050);
DISPLAY INVISIBLE (-8900 1050);
FORCEPROP 1 LAST PATH I6
J 0
(-8950 1200);
DISPLAY 0.978723 (-8950 1200);
PAINT WHITE (-8950 1200);
DISPLAY INVISIBLE (-8950 1200);
FORCEPROP 1 LAST PART_NUMBER CS11002FB07
J 0
(-8950 1150);
DISPLAY 0.978723 (-8950 1150);
PAINT SKYBLUE (-8950 1150);
DISPLAY INVISIBLE (-8950 1150);
FORCEADD UNIVERSAL_GND..1
R 2
(-2425 825);
FORCEPROP 3 LASTPIN (-2425 875) SIG_NAME GND\g
J 0
(-2415 885);
DISPLAY 0.659574 (-2415 885);
PAINT MONO (-2415 885);
DISPLAY INVISIBLE (-2415 885);
FORCEPROP 2 LAST CDS_LIB pure_quanta_power
J 0
(-2425 825);
DISPLAY INVISIBLE (-2425 825);
FORCEPROP 1 LAST HDL_POWER GND
J 1
(-2450 750);
DISPLAY 0.872340 (-2450 750);
PAINT GREEN (-2450 750);
DISPLAY INVISIBLE (-2450 750);
FORCEPROP 1 LAST PATH I60
J 2
(-2500 825);
DISPLAY 0.872340 (-2500 825);
PAINT AQUA (-2500 825);
DISPLAY INVISIBLE (-2500 825);
FORCEADD Q_RES..1
R 1
(-2425 1175);
FORCEPROP 1 LAST LOCATION R6043
R 1
J 0
(-2475 1125);
DISPLAY 0.510638 (-2475 1125);
PAINT SKYBLUE (-2475 1125);
FORCEPROP 0 LAST $SEC 1
R 1
J 0
(-2400 1300);
DISPLAY 0.680851 (-2400 1300);
PAINT MONO (-2400 1300);
DISPLAY INVISIBLE (-2400 1300);
FORCEPROP 0 LAST CDS_SEC 1
R 1
J 0
(-2400 1300);
DISPLAY 0.680851 (-2400 1300);
DISPLAY INVISIBLE (-2400 1300);
FORCEPROP 1 LASTPIN (-2425 1075) $PN 1
R 1
J 0
(-2437 1087);
DISPLAY 0.404255 (-2437 1087);
PAINT MONO (-2437 1087);
FORCEPROP 1 LASTPIN (-2425 1275) $PN 2
R 1
J 0
(-2437 1237);
DISPLAY 0.404255 (-2437 1237);
PAINT MONO (-2437 1237);
FORCEPROP 1 LAST VALUE 100K
R 1
J 2
(-2350 1200);
DISPLAY 0.510638 (-2350 1200);
PAINT SKYBLUE (-2350 1200);
FORCEPROP 1 LAST MATERIAL CHIP
R 1
J 0
(-2350 1250);
DISPLAY 0.510638 (-2350 1250);
PAINT SKYBLUE (-2350 1250);
FORCEPROP 2 LAST CDS_LIB pure_quanta
R 1
J 0
(-2425 1175);
DISPLAY INVISIBLE (-2425 1175);
FORCEPROP 1 LAST PACK_TYPE 0402LF
R 1
J 0
(-2275 1425);
DISPLAY 0.978723 (-2275 1425);
DISPLAY INVISIBLE (-2275 1425);
FORCEPROP 1 LAST WATTAGE 1/16W
R 1
J 2
(-2275 1150);
DISPLAY 0.978723 (-2275 1150);
DISPLAY INVISIBLE (-2275 1150);
FORCEPROP 1 LAST TOLERANCE 1%
R 1
J 0
(-2325 1175);
DISPLAY 0.978723 (-2325 1175);
DISPLAY INVISIBLE (-2325 1175);
FORCEPROP 1 LAST PATH I61
R 1
J 0
(-2575 1125);
DISPLAY 0.978723 (-2575 1125);
PAINT WHITE (-2575 1125);
DISPLAY INVISIBLE (-2575 1125);
FORCEPROP 1 LAST PART_NUMBER CS41002FB09
R 1
J 0
(-2525 1125);
DISPLAY 0.978723 (-2525 1125);
DISPLAY INVISIBLE (-2525 1125);
FORCEADD Q_RES..2
R 2
(-2425 1550);
FORCEPROP 1 LAST LOCATION R6042
J 2
(-2470 1675);
DISPLAY 0.489362 (-2470 1675);
PAINT SKYBLUE (-2470 1675);
FORCEPROP 0 LAST $SEC 1
J 0
(-2450 1725);
DISPLAY 0.680851 (-2450 1725);
PAINT MONO (-2450 1725);
DISPLAY INVISIBLE (-2450 1725);
FORCEPROP 0 LAST CDS_SEC 1
J 0
(-2450 1725);
DISPLAY 0.680851 (-2450 1725);
DISPLAY INVISIBLE (-2450 1725);
FORCEPROP 1 LASTPIN (-2425 1650) $PN 1
J 2
(-2430 1612);
DISPLAY 0.489362 (-2430 1612);
PAINT MONO (-2430 1612);
FORCEPROP 1 LASTPIN (-2425 1450) $PN 2
J 2
(-2430 1460);
DISPLAY 0.489362 (-2430 1460);
PAINT MONO (-2430 1460);
FORCEPROP 1 LAST VALUE 10K
J 2
(-2450 1450);
DISPLAY 0.489362 (-2450 1450);
PAINT SKYBLUE (-2450 1450);
FORCEPROP 1 LAST PACK_TYPE 0402LF
J 2
(-2465 1375);
DISPLAY 0.978723 (-2465 1375);
PAINT SKYBLUE (-2465 1375);
DISPLAY INVISIBLE (-2465 1375);
FORCEPROP 1 LAST TOLERANCE 5%
J 2
(-2470 1575);
DISPLAY 0.978723 (-2470 1575);
PAINT SKYBLUE (-2470 1575);
DISPLAY INVISIBLE (-2470 1575);
FORCEPROP 1 LAST MATERIAL CHIP
J 2
(-2465 1475);
DISPLAY 0.978723 (-2465 1475);
PAINT SKYBLUE (-2465 1475);
DISPLAY INVISIBLE (-2465 1475);
FORCEPROP 1 LAST WATTAGE 1/16W
J 2
(-2465 1525);
DISPLAY 0.978723 (-2465 1525);
PAINT SKYBLUE (-2465 1525);
DISPLAY INVISIBLE (-2465 1525);
FORCEPROP 2 LAST CDS_LIB pure_quanta
J 0
(-2425 1550);
DISPLAY INVISIBLE (-2425 1550);
FORCEPROP 1 LAST PATH I62
J 2
(-2475 1725);
DISPLAY 0.978723 (-2475 1725);
PAINT WHITE (-2475 1725);
DISPLAY INVISIBLE (-2475 1725);
FORCEPROP 1 LAST PART_NUMBER CS31002JB08
J 2
(-2465 1425);
DISPLAY 0.978723 (-2465 1425);
PAINT SKYBLUE (-2465 1425);
DISPLAY INVISIBLE (-2465 1425);
FORCEADD UNIVERSAL_POWER..1
R 2
(-2425 1750);
FORCEPROP 3 LASTPIN (-2425 1700) SIG_NAME P3V3_AUX\g
J 0
(-2415 1710);
DISPLAY 0.659574 (-2415 1710);
PAINT MONO (-2415 1710);
DISPLAY INVISIBLE (-2415 1710);
FORCEPROP 1 LAST HDL_POWER P3V3_AUX
J 1
(-2425 1800);
DISPLAY 0.489362 (-2425 1800);
PAINT GREEN (-2425 1800);
FORCEPROP 2 LAST CDS_LIB pure_quanta_power
J 0
(-2425 1750);
DISPLAY INVISIBLE (-2425 1750);
FORCEPROP 1 LAST PATH I63
J 2
(-2475 1775);
DISPLAY 0.872340 (-2475 1775);
PAINT AQUA (-2475 1775);
DISPLAY INVISIBLE (-2475 1775);
FORCEADD OFFPAGE..5
(-2300 2400);
FORCEPROP 2 LAST $XR1 28 
J 0
(-2645 2400);
DISPLAY 0.638298 (-2645 2400);
PAINT MONO (-2645 2400);
FORCEPROP 2 LAST $XR0 167 
J 0
(-2555 2400);
DISPLAY 0.638298 (-2555 2400);
PAINT MONO (-2555 2400);
FORCEPROP 2 LAST CDS_LIB standard
J 0
(-2300 2400);
DISPLAY INVISIBLE (-2300 2400);
FORCEPROP 1 LAST OFFPAGE TRUE
J 0
(-1975 2275);
DISPLAY 0.872340 (-1975 2275);
PAINT GREEN (-1975 2275);
DISPLAY INVISIBLE (-1975 2275);
FORCEPROP 1 LAST COMMENT_BODY TRUE
J 0
(-2200 2325);
DISPLAY 0.872340 (-2200 2325);
PAINT GREEN (-2200 2325);
DISPLAY INVISIBLE (-2200 2325);
FORCEPROP 2 LAST PATH I64
J 0
(-2550 2450);
DISPLAY 0.680851 (-2550 2450);
DISPLAY INVISIBLE (-2550 2450);
FORCEADD OFFPAGE..5
(-2350 3800);
FORCEPROP 2 LAST $XR1 82 
J 0
(-2725 3800);
DISPLAY 0.638298 (-2725 3800);
PAINT MONO (-2725 3800);
FORCEPROP 2 LAST $XR0 167 
J 0
(-2635 3800);
DISPLAY 0.638298 (-2635 3800);
PAINT MONO (-2635 3800);
FORCEPROP 2 LAST CDS_LIB standard
J 0
(-2350 3800);
DISPLAY INVISIBLE (-2350 3800);
FORCEPROP 1 LAST OFFPAGE TRUE
J 0
(-2025 3675);
DISPLAY 0.872340 (-2025 3675);
PAINT GREEN (-2025 3675);
DISPLAY INVISIBLE (-2025 3675);
FORCEPROP 1 LAST COMMENT_BODY TRUE
J 0
(-2250 3725);
DISPLAY 0.872340 (-2250 3725);
PAINT GREEN (-2250 3725);
DISPLAY INVISIBLE (-2250 3725);
FORCEPROP 2 LAST PATH I65
J 0
(-2600 3850);
DISPLAY 0.680851 (-2600 3850);
DISPLAY INVISIBLE (-2600 3850);
FORCEADD UNIVERSAL_GND..1
R 2
(-1000 800);
FORCEPROP 3 LASTPIN (-1000 850) SIG_NAME GND\g
J 0
(-990 860);
DISPLAY 0.659574 (-990 860);
PAINT MONO (-990 860);
DISPLAY INVISIBLE (-990 860);
FORCEPROP 2 LAST CDS_LIB pure_quanta_power
J 0
(-1000 800);
DISPLAY INVISIBLE (-1000 800);
FORCEPROP 1 LAST HDL_POWER GND
J 1
(-1025 725);
DISPLAY 0.872340 (-1025 725);
PAINT GREEN (-1025 725);
DISPLAY INVISIBLE (-1025 725);
FORCEPROP 1 LAST PATH I66
J 2
(-1075 800);
DISPLAY 0.872340 (-1075 800);
PAINT AQUA (-1075 800);
DISPLAY INVISIBLE (-1075 800);
FORCEADD OFFPAGE..5
(-1775 1250);
FORCEPROP 2 LAST $XR1 81 
J 0
(-2150 1250);
DISPLAY 0.638298 (-2150 1250);
PAINT MONO (-2150 1250);
FORCEPROP 2 LAST $XR0 167 
J 0
(-2060 1250);
DISPLAY 0.638298 (-2060 1250);
PAINT MONO (-2060 1250);
FORCEPROP 2 LAST CDS_LIB standard
J 0
(-1775 1250);
DISPLAY INVISIBLE (-1775 1250);
FORCEPROP 1 LAST OFFPAGE TRUE
J 0
(-1450 1125);
DISPLAY 0.872340 (-1450 1125);
PAINT GREEN (-1450 1125);
DISPLAY INVISIBLE (-1450 1125);
FORCEPROP 1 LAST COMMENT_BODY TRUE
J 0
(-1675 1175);
DISPLAY 0.872340 (-1675 1175);
PAINT GREEN (-1675 1175);
DISPLAY INVISIBLE (-1675 1175);
FORCEPROP 2 LAST PATH I67
J 0
(-1725 1325);
DISPLAY 0.680851 (-1725 1325);
DISPLAY INVISIBLE (-1725 1325);
FORCEADD OFFPAGE..5
(-1775 1325);
FORCEPROP 2 LAST $XR0 167 
J 0
(-2060 1325);
DISPLAY 0.638298 (-2060 1325);
PAINT MONO (-2060 1325);
FORCEPROP 2 LAST CDS_LIB standard
J 0
(-1775 1325);
DISPLAY INVISIBLE (-1775 1325);
FORCEPROP 1 LAST OFFPAGE TRUE
J 0
(-1450 1200);
DISPLAY 0.872340 (-1450 1200);
PAINT GREEN (-1450 1200);
DISPLAY INVISIBLE (-1450 1200);
FORCEPROP 1 LAST COMMENT_BODY TRUE
J 0
(-1675 1250);
DISPLAY 0.872340 (-1675 1250);
PAINT GREEN (-1675 1250);
DISPLAY INVISIBLE (-1675 1250);
FORCEPROP 2 LAST PATH I68
J 0
(-1725 1400);
DISPLAY 0.680851 (-1725 1400);
DISPLAY INVISIBLE (-1725 1400);
FORCEADD Q_RES..1
R 1
(-1000 1150);
FORCEPROP 1 LAST LOCATION R6041
R 1
J 0
(-1050 1100);
DISPLAY 0.510638 (-1050 1100);
PAINT SKYBLUE (-1050 1100);
FORCEPROP 0 LAST $SEC 1
R 1
J 0
(-975 1275);
DISPLAY 0.680851 (-975 1275);
PAINT MONO (-975 1275);
DISPLAY INVISIBLE (-975 1275);
FORCEPROP 0 LAST CDS_SEC 1
R 1
J 0
(-975 1275);
DISPLAY 0.680851 (-975 1275);
DISPLAY INVISIBLE (-975 1275);
FORCEPROP 1 LASTPIN (-1000 1050) $PN 1
R 1
J 0
(-1012 1062);
DISPLAY 0.404255 (-1012 1062);
PAINT MONO (-1012 1062);
FORCEPROP 1 LASTPIN (-1000 1250) $PN 2
R 1
J 0
(-1012 1212);
DISPLAY 0.404255 (-1012 1212);
PAINT MONO (-1012 1212);
FORCEPROP 1 LAST VALUE 100K
R 1
J 2
(-925 1175);
DISPLAY 0.510638 (-925 1175);
PAINT SKYBLUE (-925 1175);
FORCEPROP 1 LAST MATERIAL CHIP
R 1
J 0
(-925 1225);
DISPLAY 0.510638 (-925 1225);
PAINT SKYBLUE (-925 1225);
FORCEPROP 1 LAST TOLERANCE 1%
R 1
J 0
(-900 1150);
DISPLAY 0.978723 (-900 1150);
DISPLAY INVISIBLE (-900 1150);
FORCEPROP 1 LAST WATTAGE 1/16W
R 1
J 2
(-850 1125);
DISPLAY 0.978723 (-850 1125);
DISPLAY INVISIBLE (-850 1125);
FORCEPROP 1 LAST PACK_TYPE 0402LF
R 1
J 0
(-850 1400);
DISPLAY 0.978723 (-850 1400);
DISPLAY INVISIBLE (-850 1400);
FORCEPROP 2 LAST CDS_LIB pure_quanta
R 1
J 0
(-1000 1150);
DISPLAY INVISIBLE (-1000 1150);
FORCEPROP 1 LAST PATH I69
R 1
J 0
(-1150 1100);
DISPLAY 0.978723 (-1150 1100);
PAINT WHITE (-1150 1100);
DISPLAY INVISIBLE (-1150 1100);
FORCEPROP 1 LAST PART_NUMBER CS41002FB09
R 1
J 0
(-1100 1100);
DISPLAY 0.978723 (-1100 1100);
DISPLAY INVISIBLE (-1100 1100);
FORCEADD OFFPAGE..1
(-8800 1100);
FORCEPROP 2 LAST $XR0 167 
J 0
(-9052 1100);
DISPLAY 0.638298 (-9052 1100);
PAINT MONO (-9052 1100);
FORCEPROP 2 LAST CDS_LIB standard
J 0
(-8800 1100);
DISPLAY INVISIBLE (-8800 1100);
FORCEPROP 1 LAST OFFPAGE TRUE
J 0
(-8475 975);
DISPLAY 0.872340 (-8475 975);
PAINT GREEN (-8475 975);
DISPLAY INVISIBLE (-8475 975);
FORCEPROP 1 LAST COMMENT_BODY TRUE
J 0
(-8675 1000);
DISPLAY 0.872340 (-8675 1000);
PAINT GREEN (-8675 1000);
DISPLAY INVISIBLE (-8675 1000);
FORCEPROP 2 LAST PATH I7
J 0
(-9000 1150);
DISPLAY 0.680851 (-9000 1150);
DISPLAY INVISIBLE (-9000 1150);
FORCEADD Q_RES..2
R 2
(-1000 1525);
FORCEPROP 1 LAST LOCATION R6040
J 2
(-1045 1650);
DISPLAY 0.489362 (-1045 1650);
PAINT SKYBLUE (-1045 1650);
FORCEPROP 0 LAST $SEC 1
J 0
(-1025 1700);
DISPLAY 0.680851 (-1025 1700);
PAINT MONO (-1025 1700);
DISPLAY INVISIBLE (-1025 1700);
FORCEPROP 0 LAST CDS_SEC 1
J 0
(-1025 1700);
DISPLAY 0.680851 (-1025 1700);
DISPLAY INVISIBLE (-1025 1700);
FORCEPROP 1 LASTPIN (-1000 1625) $PN 1
J 2
(-1005 1587);
DISPLAY 0.489362 (-1005 1587);
PAINT MONO (-1005 1587);
FORCEPROP 1 LASTPIN (-1000 1425) $PN 2
J 2
(-1005 1435);
DISPLAY 0.489362 (-1005 1435);
PAINT MONO (-1005 1435);
FORCEPROP 1 LAST VALUE 10K
J 2
(-1025 1425);
DISPLAY 0.489362 (-1025 1425);
PAINT SKYBLUE (-1025 1425);
FORCEPROP 2 LAST CDS_LIB pure_quanta
J 0
(-1000 1525);
DISPLAY INVISIBLE (-1000 1525);
FORCEPROP 1 LAST WATTAGE 1/16W
J 2
(-1040 1500);
DISPLAY 0.978723 (-1040 1500);
PAINT SKYBLUE (-1040 1500);
DISPLAY INVISIBLE (-1040 1500);
FORCEPROP 1 LAST MATERIAL CHIP
J 2
(-1040 1450);
DISPLAY 0.978723 (-1040 1450);
PAINT SKYBLUE (-1040 1450);
DISPLAY INVISIBLE (-1040 1450);
FORCEPROP 1 LAST TOLERANCE 5%
J 2
(-1045 1550);
DISPLAY 0.978723 (-1045 1550);
PAINT SKYBLUE (-1045 1550);
DISPLAY INVISIBLE (-1045 1550);
FORCEPROP 1 LAST PACK_TYPE 0402LF
J 2
(-1040 1350);
DISPLAY 0.978723 (-1040 1350);
PAINT SKYBLUE (-1040 1350);
DISPLAY INVISIBLE (-1040 1350);
FORCEPROP 1 LAST PATH I70
J 2
(-1050 1700);
DISPLAY 0.978723 (-1050 1700);
PAINT WHITE (-1050 1700);
DISPLAY INVISIBLE (-1050 1700);
FORCEPROP 1 LAST PART_NUMBER CS31002JB08
J 2
(-1040 1400);
DISPLAY 0.978723 (-1040 1400);
PAINT SKYBLUE (-1040 1400);
DISPLAY INVISIBLE (-1040 1400);
FORCEADD UNIVERSAL_POWER..1
R 2
(-1000 1725);
FORCEPROP 3 LASTPIN (-1000 1675) SIG_NAME P1V8_AUX\g
J 0
(-990 1685);
DISPLAY 0.659574 (-990 1685);
PAINT MONO (-990 1685);
DISPLAY INVISIBLE (-990 1685);
FORCEPROP 1 LAST HDL_POWER P1V8_AUX
J 1
(-1000 1775);
DISPLAY 0.489362 (-1000 1775);
PAINT GREEN (-1000 1775);
FORCEPROP 2 LAST CDS_LIB pure_quanta_power
J 0
(-1000 1725);
DISPLAY INVISIBLE (-1000 1725);
FORCEPROP 1 LAST PATH I71
J 2
(-1050 1750);
DISPLAY 0.872340 (-1050 1750);
PAINT AQUA (-1050 1750);
DISPLAY INVISIBLE (-1050 1750);
FORCEADD Q_RES..2
R 2
(-1525 2600);
FORCEPROP 1 LAST LOCATION R1358
J 2
(-1570 2725);
DISPLAY 0.489362 (-1570 2725);
PAINT SKYBLUE (-1570 2725);
FORCEPROP 0 LAST $SEC 1
J 0
(-1550 2775);
DISPLAY 0.680851 (-1550 2775);
PAINT MONO (-1550 2775);
DISPLAY INVISIBLE (-1550 2775);
FORCEPROP 0 LAST CDS_SEC 1
J 0
(-1550 2775);
DISPLAY 0.680851 (-1550 2775);
DISPLAY INVISIBLE (-1550 2775);
FORCEPROP 1 LASTPIN (-1525 2700) $PN 1
J 2
(-1530 2662);
DISPLAY 0.489362 (-1530 2662);
PAINT MONO (-1530 2662);
FORCEPROP 1 LASTPIN (-1525 2500) $PN 2
J 2
(-1530 2510);
DISPLAY 0.489362 (-1530 2510);
PAINT MONO (-1530 2510);
FORCEPROP 1 LAST VALUE 10K
J 2
(-1550 2500);
DISPLAY 0.489362 (-1550 2500);
PAINT SKYBLUE (-1550 2500);
FORCEPROP 1 LAST PACK_TYPE 0402LF
J 2
(-1565 2425);
DISPLAY 0.978723 (-1565 2425);
PAINT SKYBLUE (-1565 2425);
DISPLAY INVISIBLE (-1565 2425);
FORCEPROP 1 LAST TOLERANCE 5%
J 2
(-1570 2625);
DISPLAY 0.978723 (-1570 2625);
PAINT SKYBLUE (-1570 2625);
DISPLAY INVISIBLE (-1570 2625);
FORCEPROP 1 LAST WATTAGE 1/16W
J 2
(-1565 2575);
DISPLAY 0.978723 (-1565 2575);
PAINT SKYBLUE (-1565 2575);
DISPLAY INVISIBLE (-1565 2575);
FORCEPROP 2 LAST CDS_LIB pure_quanta
J 0
(-1525 2600);
DISPLAY INVISIBLE (-1525 2600);
FORCEPROP 1 LAST MATERIAL EMPTY
J 2
(-1565 2525);
DISPLAY 0.978723 (-1565 2525);
PAINT SKYBLUE (-1565 2525);
DISPLAY INVISIBLE (-1565 2525);
FORCEPROP 1 LAST PATH I72
J 2
(-1575 2775);
DISPLAY 0.978723 (-1575 2775);
PAINT WHITE (-1575 2775);
DISPLAY INVISIBLE (-1575 2775);
FORCEPROP 1 LAST PART_NUMBER CS31002JB08
J 2
(-1565 2475);
DISPLAY 0.978723 (-1565 2475);
PAINT SKYBLUE (-1565 2475);
DISPLAY INVISIBLE (-1565 2475);
FORCEADD UNIVERSAL_POWER..1
R 2
(-1525 2800);
FORCEPROP 3 LASTPIN (-1525 2750) SIG_NAME P1V8_AUX\g
J 0
(-1515 2760);
DISPLAY 0.659574 (-1515 2760);
PAINT MONO (-1515 2760);
DISPLAY INVISIBLE (-1515 2760);
FORCEPROP 1 LAST HDL_POWER P1V8_AUX
J 1
(-1525 2850);
DISPLAY 0.489362 (-1525 2850);
PAINT GREEN (-1525 2850);
FORCEPROP 2 LAST CDS_LIB pure_quanta_power
J 0
(-1525 2800);
DISPLAY INVISIBLE (-1525 2800);
FORCEPROP 1 LAST PATH I73
J 2
(-1575 2825);
DISPLAY 0.872340 (-1575 2825);
PAINT AQUA (-1575 2825);
DISPLAY INVISIBLE (-1575 2825);
FORCEADD Q_RES..2
(-1775 4100);
FORCEPROP 1 LAST LOCATION R1357
J 0
(-1730 4225);
DISPLAY 0.489362 (-1730 4225);
PAINT SKYBLUE (-1730 4225);
FORCEPROP 0 LAST $SEC 1
J 0
(-1725 4275);
DISPLAY 0.680851 (-1725 4275);
PAINT MONO (-1725 4275);
DISPLAY INVISIBLE (-1725 4275);
FORCEPROP 0 LAST CDS_SEC 1
J 0
(-1725 4275);
DISPLAY 0.680851 (-1725 4275);
DISPLAY INVISIBLE (-1725 4275);
FORCEPROP 1 LASTPIN (-1775 4200) $PN 1
J 0
(-1770 4162);
DISPLAY 0.489362 (-1770 4162);
PAINT MONO (-1770 4162);
FORCEPROP 1 LASTPIN (-1775 4000) $PN 2
J 0
(-1770 4010);
DISPLAY 0.489362 (-1770 4010);
PAINT MONO (-1770 4010);
FORCEPROP 1 LAST MATERIAL CHIP
J 0
(-1725 4075);
DISPLAY 0.489362 (-1725 4075);
PAINT SKYBLUE (-1725 4075);
FORCEPROP 1 LAST TOLERANCE 5%
J 0
(-1725 4125);
DISPLAY 0.489362 (-1725 4125);
PAINT SKYBLUE (-1725 4125);
FORCEPROP 1 LAST PACK_TYPE 0402LF
J 0
(-1725 4050);
DISPLAY 0.489362 (-1725 4050);
PAINT SKYBLUE (-1725 4050);
FORCEPROP 1 LAST WATTAGE 1/16W
J 0
(-1725 4100);
DISPLAY 0.489362 (-1725 4100);
PAINT SKYBLUE (-1725 4100);
FORCEPROP 1 LAST VALUE 2.2K
J 0
(-1725 4150);
DISPLAY 0.489362 (-1725 4150);
PAINT SKYBLUE (-1725 4150);
FORCEPROP 2 LAST CDS_LIB pure_quanta
J 0
(-1775 4100);
DISPLAY INVISIBLE (-1775 4100);
FORCEPROP 1 LAST PATH I74
J 0
(-1725 4275);
DISPLAY 0.978723 (-1725 4275);
PAINT WHITE (-1725 4275);
DISPLAY INVISIBLE (-1725 4275);
FORCEPROP 1 LAST PART_NUMBER CS22202JB07
J 0
(-1725 4025);
DISPLAY 0.489362 (-1725 4025);
PAINT SKYBLUE (-1725 4025);
DISPLAY INVISIBLE (-1725 4025);
FORCEADD OFFPAGE..5
(-2375 5450);
FORCEPROP 2 LAST $XR1 82 
J 0
(-2720 5450);
DISPLAY 0.638298 (-2720 5450);
PAINT MONO (-2720 5450);
FORCEPROP 2 LAST $XR0 167 
J 0
(-2630 5450);
DISPLAY 0.638298 (-2630 5450);
PAINT MONO (-2630 5450);
FORCEPROP 2 LAST CDS_LIB standard
J 0
(-2375 5450);
DISPLAY INVISIBLE (-2375 5450);
FORCEPROP 1 LAST OFFPAGE TRUE
J 0
(-2050 5325);
DISPLAY 0.872340 (-2050 5325);
PAINT GREEN (-2050 5325);
DISPLAY INVISIBLE (-2050 5325);
FORCEPROP 1 LAST COMMENT_BODY TRUE
J 0
(-2275 5375);
DISPLAY 0.872340 (-2275 5375);
PAINT GREEN (-2275 5375);
DISPLAY INVISIBLE (-2275 5375);
FORCEPROP 2 LAST PATH I75
J 0
(-2650 5500);
DISPLAY 0.680851 (-2650 5500);
DISPLAY INVISIBLE (-2650 5500);
FORCEADD UNIVERSAL_POWER..1
(-1775 4350);
FORCEPROP 3 LASTPIN (-1775 4300) SIG_NAME P3V3_AUX\g
J 0
(-1765 4310);
DISPLAY 0.659574 (-1765 4310);
PAINT MONO (-1765 4310);
DISPLAY INVISIBLE (-1765 4310);
FORCEPROP 1 LAST HDL_POWER P3V3_AUX
J 1
(-1775 4400);
DISPLAY 0.489362 (-1775 4400);
PAINT GREEN (-1775 4400);
FORCEPROP 2 LAST CDS_LIB pure_quanta_power
J 0
(-1775 4350);
DISPLAY INVISIBLE (-1775 4350);
FORCEPROP 1 LAST PATH I76
J 0
(-1725 4375);
DISPLAY 0.872340 (-1725 4375);
PAINT AQUA (-1725 4375);
DISPLAY INVISIBLE (-1725 4375);
FORCEADD Q_RES..2
(-1775 5750);
FORCEPROP 1 LAST LOCATION R1356
J 0
(-1730 5875);
DISPLAY 0.489362 (-1730 5875);
PAINT SKYBLUE (-1730 5875);
FORCEPROP 0 LAST $SEC 1
J 0
(-1725 5925);
DISPLAY 0.680851 (-1725 5925);
PAINT MONO (-1725 5925);
DISPLAY INVISIBLE (-1725 5925);
FORCEPROP 0 LAST CDS_SEC 1
J 0
(-1725 5925);
DISPLAY 0.680851 (-1725 5925);
DISPLAY INVISIBLE (-1725 5925);
FORCEPROP 1 LASTPIN (-1775 5850) $PN 1
J 0
(-1770 5812);
DISPLAY 0.489362 (-1770 5812);
PAINT MONO (-1770 5812);
FORCEPROP 1 LASTPIN (-1775 5650) $PN 2
J 0
(-1770 5660);
DISPLAY 0.489362 (-1770 5660);
PAINT MONO (-1770 5660);
FORCEPROP 1 LAST PACK_TYPE 0402LF
J 0
(-1725 5700);
DISPLAY 0.489362 (-1725 5700);
PAINT SKYBLUE (-1725 5700);
FORCEPROP 1 LAST VALUE 4.7K
J 0
(-1725 5800);
DISPLAY 0.489362 (-1725 5800);
PAINT SKYBLUE (-1725 5800);
FORCEPROP 1 LAST TOLERANCE 5%
J 0
(-1725 5775);
DISPLAY 0.489362 (-1725 5775);
PAINT SKYBLUE (-1725 5775);
FORCEPROP 1 LAST MATERIAL CHIP
J 0
(-1725 5725);
DISPLAY 0.489362 (-1725 5725);
PAINT SKYBLUE (-1725 5725);
FORCEPROP 1 LAST WATTAGE 1/16W
J 0
(-1725 5750);
DISPLAY 0.489362 (-1725 5750);
PAINT SKYBLUE (-1725 5750);
FORCEPROP 2 LAST CDS_LIB pure_quanta
J 0
(-1775 5750);
DISPLAY INVISIBLE (-1775 5750);
FORCEPROP 1 LAST PATH I77
J 0
(-1725 5925);
DISPLAY 0.978723 (-1725 5925);
PAINT WHITE (-1725 5925);
DISPLAY INVISIBLE (-1725 5925);
FORCEPROP 1 LAST PART_NUMBER CS24702JB10
J 0
(-1725 5675);
DISPLAY 0.489362 (-1725 5675);
PAINT SKYBLUE (-1725 5675);
DISPLAY INVISIBLE (-1725 5675);
FORCEADD UNIVERSAL_POWER..1
(-1775 6000);
FORCEPROP 3 LASTPIN (-1775 5950) SIG_NAME P3V3_AUX\g
J 0
(-1765 5960);
DISPLAY 0.659574 (-1765 5960);
PAINT MONO (-1765 5960);
DISPLAY INVISIBLE (-1765 5960);
FORCEPROP 1 LAST HDL_POWER P3V3_AUX
J 1
(-1775 6050);
DISPLAY 0.489362 (-1775 6050);
PAINT GREEN (-1775 6050);
FORCEPROP 2 LAST CDS_LIB pure_quanta_power
J 0
(-1775 6000);
DISPLAY INVISIBLE (-1775 6000);
FORCEPROP 1 LAST PATH I78
J 0
(-1725 6025);
DISPLAY 0.872340 (-1725 6025);
PAINT AQUA (-1725 6025);
DISPLAY INVISIBLE (-1725 6025);
FORCEADD UNIVERSAL_GND..1
R 5
(-8200 1300);
FORCEPROP 3 LASTPIN (-8150 1300) SIG_NAME GND\g
J 0
(-8140 1310);
DISPLAY 0.659574 (-8140 1310);
PAINT MONO (-8140 1310);
DISPLAY INVISIBLE (-8140 1310);
FORCEPROP 2 LAST CDS_LIB pure_quanta_power
R 3
J 2
(-8200 1300);
DISPLAY INVISIBLE (-8200 1300);
FORCEPROP 1 LAST HDL_POWER GND
R 3
J 1
(-8275 1275);
DISPLAY 0.872340 (-8275 1275);
PAINT GREEN (-8275 1275);
DISPLAY INVISIBLE (-8275 1275);
FORCEPROP 1 LAST PATH I79
R 3
J 0
(-8200 1225);
DISPLAY 0.872340 (-8200 1225);
PAINT AQUA (-8200 1225);
DISPLAY INVISIBLE (-8200 1225);
FORCEADD OFFPAGE..1
(-8800 1150);
FORCEPROP 2 LAST $XR0 167 
J 0
(-9052 1150);
DISPLAY 0.638298 (-9052 1150);
PAINT MONO (-9052 1150);
FORCEPROP 2 LAST CDS_LIB standard
J 0
(-8800 1150);
DISPLAY INVISIBLE (-8800 1150);
FORCEPROP 1 LAST OFFPAGE TRUE
J 0
(-8475 1025);
DISPLAY 0.872340 (-8475 1025);
PAINT GREEN (-8475 1025);
DISPLAY INVISIBLE (-8475 1025);
FORCEPROP 1 LAST COMMENT_BODY TRUE
J 0
(-8675 1050);
DISPLAY 0.872340 (-8675 1050);
PAINT GREEN (-8675 1050);
DISPLAY INVISIBLE (-8675 1050);
FORCEPROP 2 LAST PATH I8
J 0
(-9050 1200);
DISPLAY 0.680851 (-9050 1200);
DISPLAY INVISIBLE (-9050 1200);
FORCEADD UNIVERSAL_POWER..1
R 2
(-1100 2800);
FORCEPROP 3 LASTPIN (-1100 2750) SIG_NAME PVDD18_S5_P0\g
J 0
(-1090 2760);
DISPLAY 0.659574 (-1090 2760);
PAINT MONO (-1090 2760);
DISPLAY INVISIBLE (-1090 2760);
FORCEPROP 1 LAST HDL_POWER PVDD18_S5_P0
J 1
(-1100 2850);
DISPLAY 0.489362 (-1100 2850);
PAINT GREEN (-1100 2850);
FORCEPROP 2 LAST CDS_LIB pure_quanta_power
J 0
(-1100 2800);
DISPLAY INVISIBLE (-1100 2800);
FORCEPROP 1 LAST PATH I80
J 2
(-1150 2825);
DISPLAY 0.872340 (-1150 2825);
PAINT AQUA (-1150 2825);
DISPLAY INVISIBLE (-1150 2825);
FORCEADD Q_RES..2
R 2
(-1100 2600);
FORCEPROP 1 LAST LOCATION R6106
J 2
(-1145 2725);
DISPLAY 0.489362 (-1145 2725);
PAINT SKYBLUE (-1145 2725);
FORCEPROP 0 LAST $SEC 1
J 0
(-1125 2775);
DISPLAY 0.680851 (-1125 2775);
PAINT MONO (-1125 2775);
DISPLAY INVISIBLE (-1125 2775);
FORCEPROP 0 LAST CDS_SEC 1
J 0
(-1125 2775);
DISPLAY 0.680851 (-1125 2775);
DISPLAY INVISIBLE (-1125 2775);
FORCEPROP 1 LASTPIN (-1100 2700) $PN 1
J 2
(-1105 2662);
DISPLAY 0.489362 (-1105 2662);
PAINT MONO (-1105 2662);
FORCEPROP 1 LASTPIN (-1100 2500) $PN 2
J 2
(-1105 2510);
DISPLAY 0.489362 (-1105 2510);
PAINT MONO (-1105 2510);
FORCEPROP 1 LAST VALUE 10K
J 2
(-1125 2500);
DISPLAY 0.489362 (-1125 2500);
PAINT SKYBLUE (-1125 2500);
FORCEPROP 1 LAST PACK_TYPE 0402LF
J 2
(-1140 2425);
DISPLAY 0.978723 (-1140 2425);
PAINT SKYBLUE (-1140 2425);
DISPLAY INVISIBLE (-1140 2425);
FORCEPROP 1 LAST TOLERANCE 5%
J 2
(-1145 2625);
DISPLAY 0.978723 (-1145 2625);
PAINT SKYBLUE (-1145 2625);
DISPLAY INVISIBLE (-1145 2625);
FORCEPROP 1 LAST MATERIAL CHIP
J 2
(-1140 2525);
DISPLAY 0.978723 (-1140 2525);
PAINT SKYBLUE (-1140 2525);
DISPLAY INVISIBLE (-1140 2525);
FORCEPROP 1 LAST WATTAGE 1/16W
J 2
(-1140 2575);
DISPLAY 0.978723 (-1140 2575);
PAINT SKYBLUE (-1140 2575);
DISPLAY INVISIBLE (-1140 2575);
FORCEPROP 2 LAST CDS_LIB pure_quanta
J 0
(-1100 2600);
DISPLAY INVISIBLE (-1100 2600);
FORCEPROP 1 LAST PATH I81
J 2
(-1150 2775);
DISPLAY 0.978723 (-1150 2775);
PAINT WHITE (-1150 2775);
DISPLAY INVISIBLE (-1150 2775);
FORCEPROP 1 LAST PART_NUMBER CS31002JB08
J 2
(-1140 2475);
DISPLAY 0.978723 (-1140 2475);
PAINT SKYBLUE (-1140 2475);
DISPLAY INVISIBLE (-1140 2475);
FORCEADD UNIVERSAL_POWER..1
R 2
(-4600 2650);
FORCEPROP 3 LASTPIN (-4600 2600) SIG_NAME PVDD18_S5_P0\g
J 0
(-4590 2610);
DISPLAY 0.659574 (-4590 2610);
PAINT MONO (-4590 2610);
DISPLAY INVISIBLE (-4590 2610);
FORCEPROP 1 LAST HDL_POWER PVDD18_S5_P0
J 1
(-4600 2700);
DISPLAY 0.489362 (-4600 2700);
PAINT GREEN (-4600 2700);
FORCEPROP 2 LAST CDS_LIB pure_quanta_power
J 0
(-4600 2650);
DISPLAY INVISIBLE (-4600 2650);
FORCEPROP 1 LAST PATH I82
J 2
(-4650 2675);
DISPLAY 0.872340 (-4650 2675);
PAINT AQUA (-4650 2675);
DISPLAY INVISIBLE (-4650 2675);
FORCEADD Q_RES..2
R 2
(-4600 2450);
FORCEPROP 1 LAST LOCATION R6107
J 2
(-4645 2575);
DISPLAY 0.489362 (-4645 2575);
PAINT SKYBLUE (-4645 2575);
FORCEPROP 0 LAST $SEC 1
J 0
(-4625 2625);
DISPLAY 0.680851 (-4625 2625);
PAINT MONO (-4625 2625);
DISPLAY INVISIBLE (-4625 2625);
FORCEPROP 0 LAST CDS_SEC 1
J 0
(-4625 2625);
DISPLAY 0.680851 (-4625 2625);
DISPLAY INVISIBLE (-4625 2625);
FORCEPROP 1 LASTPIN (-4600 2550) $PN 1
J 2
(-4605 2512);
DISPLAY 0.489362 (-4605 2512);
PAINT MONO (-4605 2512);
FORCEPROP 1 LASTPIN (-4600 2350) $PN 2
J 2
(-4605 2360);
DISPLAY 0.489362 (-4605 2360);
PAINT MONO (-4605 2360);
FORCEPROP 1 LAST VALUE 10K
J 2
(-4625 2350);
DISPLAY 0.489362 (-4625 2350);
PAINT SKYBLUE (-4625 2350);
FORCEPROP 2 LAST CDS_LIB pure_quanta
J 0
(-4600 2450);
DISPLAY INVISIBLE (-4600 2450);
FORCEPROP 1 LAST WATTAGE 1/16W
J 2
(-4640 2425);
DISPLAY 0.978723 (-4640 2425);
PAINT SKYBLUE (-4640 2425);
DISPLAY INVISIBLE (-4640 2425);
FORCEPROP 1 LAST MATERIAL CHIP
J 2
(-4640 2375);
DISPLAY 0.978723 (-4640 2375);
PAINT SKYBLUE (-4640 2375);
DISPLAY INVISIBLE (-4640 2375);
FORCEPROP 1 LAST TOLERANCE 5%
J 2
(-4645 2475);
DISPLAY 0.978723 (-4645 2475);
PAINT SKYBLUE (-4645 2475);
DISPLAY INVISIBLE (-4645 2475);
FORCEPROP 1 LAST PACK_TYPE 0402LF
J 2
(-4640 2275);
DISPLAY 0.978723 (-4640 2275);
PAINT SKYBLUE (-4640 2275);
DISPLAY INVISIBLE (-4640 2275);
FORCEPROP 1 LAST PATH I83
J 2
(-4650 2625);
DISPLAY 0.978723 (-4650 2625);
PAINT WHITE (-4650 2625);
DISPLAY INVISIBLE (-4650 2625);
FORCEPROP 1 LAST PART_NUMBER CS31002JB08
J 2
(-4640 2325);
DISPLAY 0.978723 (-4640 2325);
PAINT SKYBLUE (-4640 2325);
DISPLAY INVISIBLE (-4640 2325);
FORCEADD Q_RES..2
(-4500 1550);
FORCEPROP 1 LAST LOCATION R8018
J 0
(-4455 1675);
DISPLAY 0.638298 (-4455 1675);
FORCEPROP 0 LAST $SEC 1
J 0
(-4450 1725);
DISPLAY 0.680851 (-4450 1725);
PAINT MONO (-4450 1725);
DISPLAY INVISIBLE (-4450 1725);
FORCEPROP 0 LAST CDS_SEC 1
J 0
(-4450 1725);
DISPLAY 0.680851 (-4450 1725);
DISPLAY INVISIBLE (-4450 1725);
FORCEPROP 1 LASTPIN (-4500 1650) $PN 1
J 0
(-4495 1612);
DISPLAY 0.787234 (-4495 1612);
PAINT MONO (-4495 1612);
FORCEPROP 1 LASTPIN (-4500 1450) $PN 2
J 0
(-4495 1460);
DISPLAY 0.787234 (-4495 1460);
PAINT MONO (-4495 1460);
FORCEPROP 1 LAST VALUE 0
J 0
(-4455 1625);
DISPLAY 0.638298 (-4455 1625);
FORCEPROP 1 LAST MATERIAL CHIP
J 0
(-4460 1475);
DISPLAY 0.638298 (-4460 1475);
FORCEPROP 1 LAST TOLERANCE 5%
J 0
(-4455 1575);
DISPLAY 0.638298 (-4455 1575);
FORCEPROP 1 LAST WATTAGE 1/16W
J 0
(-4460 1525);
DISPLAY 0.638298 (-4460 1525);
FORCEPROP 1 LAST PACK_TYPE 0402LF
J 0
(-4460 1375);
DISPLAY 0.638298 (-4460 1375);
FORCEPROP 2 LAST CDS_LIB pure_quanta
J 0
(-4500 1550);
DISPLAY INVISIBLE (-4500 1550);
FORCEPROP 1 LAST PATH I84
J 0
(-4450 1725);
DISPLAY 0.978723 (-4450 1725);
PAINT WHITE (-4450 1725);
DISPLAY INVISIBLE (-4450 1725);
FORCEPROP 1 LAST PART_NUMBER CS00002JB13
J 0
(-4460 1425);
DISPLAY 0.638298 (-4460 1425);
DISPLAY INVISIBLE (-4460 1425);
FORCEADD Q_RES..2
R 2
(-4750 1550);
FORCEPROP 1 LAST LOCATION R8017
J 2
(-4795 1675);
DISPLAY 0.638298 (-4795 1675);
FORCEPROP 2 LAST SEC 1
J 0
(-4800 1775);
DISPLAY 0.680851 (-4800 1775);
PAINT MONO (-4800 1775);
DISPLAY INVISIBLE (-4800 1775);
FORCEPROP 1 LASTPIN (-4750 1650) $PN 1
J 2
(-4755 1612);
DISPLAY 0.787234 (-4755 1612);
PAINT MONO (-4755 1612);
FORCEPROP 1 LASTPIN (-4750 1450) $PN 2
J 2
(-4755 1460);
DISPLAY 0.787234 (-4755 1460);
PAINT MONO (-4755 1460);
FORCEPROP 1 LAST VALUE 0
J 2
(-4795 1625);
DISPLAY 0.638298 (-4795 1625);
FORCEPROP 1 LAST TOLERANCE 5%
J 2
(-4795 1575);
DISPLAY 0.638298 (-4795 1575);
FORCEPROP 1 LAST PACK_TYPE 0402LF
J 2
(-4790 1375);
DISPLAY 0.638298 (-4790 1375);
FORCEPROP 1 LAST MATERIAL EMPTY
J 2
(-4790 1475);
DISPLAY 0.638298 (-4790 1475);
FORCEPROP 1 LAST WATTAGE 1/16W
J 2
(-4790 1525);
DISPLAY 0.638298 (-4790 1525);
FORCEPROP 2 LAST SEC_TYPE 0402LF
J 0
(-4800 1775);
DISPLAY 0.680851 (-4800 1775);
DISPLAY INVISIBLE (-4800 1775);
FORCEPROP 2 LAST CDS_LIB pure_quanta
J 2
(-4750 1550);
DISPLAY INVISIBLE (-4750 1550);
FORCEPROP 1 LAST PATH I85
J 2
(-4800 1725);
DISPLAY 0.978723 (-4800 1725);
PAINT WHITE (-4800 1725);
DISPLAY INVISIBLE (-4800 1725);
FORCEPROP 1 LAST PART_NUMBER CS00002JB13
J 2
(-4790 1425);
DISPLAY 0.638298 (-4790 1425);
DISPLAY INVISIBLE (-4790 1425);
FORCEADD UNIVERSAL_POWER..1
R 2
(-4500 1825);
FORCEPROP 3 LASTPIN (-4500 1775) SIG_NAME P1V8_AUX\g
J 0
(-4490 1785);
DISPLAY 0.659574 (-4490 1785);
PAINT MONO (-4490 1785);
DISPLAY INVISIBLE (-4490 1785);
FORCEPROP 1 LAST HDL_POWER P1V8_AUX
J 1
(-4500 1875);
DISPLAY 0.489362 (-4500 1875);
PAINT GREEN (-4500 1875);
FORCEPROP 2 LAST CDS_LIB pure_quanta_power
J 0
(-4500 1825);
DISPLAY INVISIBLE (-4500 1825);
FORCEPROP 1 LAST PATH I86
J 2
(-4550 1850);
DISPLAY 0.872340 (-4550 1850);
PAINT AQUA (-4550 1850);
DISPLAY INVISIBLE (-4550 1850);
FORCEADD UNIVERSAL_POWER..1
R 2
(-5475 1225);
FORCEPROP 3 LASTPIN (-5475 1175) SIG_NAME P3V3_AUX\g
J 0
(-5465 1185);
DISPLAY 0.659574 (-5465 1185);
PAINT MONO (-5465 1185);
DISPLAY INVISIBLE (-5465 1185);
FORCEPROP 1 LAST HDL_POWER P3V3_AUX
J 1
(-5475 1275);
DISPLAY 0.489362 (-5475 1275);
PAINT GREEN (-5475 1275);
FORCEPROP 2 LAST CDS_LIB pure_quanta_power
J 0
(-5475 1225);
DISPLAY INVISIBLE (-5475 1225);
FORCEPROP 1 LAST PATH I87
J 2
(-5525 1250);
DISPLAY 0.872340 (-5525 1250);
PAINT AQUA (-5525 1250);
DISPLAY INVISIBLE (-5525 1250);
FORCEADD Q_RES..2
(-5475 1000);
FORCEPROP 1 LAST LOCATION R8019
J 0
(-5430 1125);
DISPLAY 0.617021 (-5430 1125);
PAINT SKYBLUE (-5430 1125);
FORCEPROP 0 LAST $SEC 1
J 0
(-5425 1175);
DISPLAY 0.680851 (-5425 1175);
PAINT MONO (-5425 1175);
DISPLAY INVISIBLE (-5425 1175);
FORCEPROP 0 LAST CDS_SEC 1
J 0
(-5425 1175);
DISPLAY 0.680851 (-5425 1175);
DISPLAY INVISIBLE (-5425 1175);
FORCEPROP 1 LASTPIN (-5475 1100) $PN 1
J 0
(-5470 1062);
DISPLAY 0.787234 (-5470 1062);
PAINT MONO (-5470 1062);
FORCEPROP 1 LASTPIN (-5475 900) $PN 2
J 0
(-5470 910);
DISPLAY 0.787234 (-5470 910);
PAINT MONO (-5470 910);
FORCEPROP 1 LAST VALUE 100
J 0
(-5430 1075);
DISPLAY 0.489362 (-5430 1075);
PAINT SKYBLUE (-5430 1075);
FORCEPROP 1 LAST TOLERANCE 1%
J 0
(-5430 1025);
DISPLAY 0.489362 (-5430 1025);
PAINT SKYBLUE (-5430 1025);
FORCEPROP 1 LAST PACK_TYPE 0402LF
J 0
(-5425 875);
DISPLAY 0.489362 (-5425 875);
PAINT SKYBLUE (-5425 875);
FORCEPROP 1 LAST MATERIAL EMPTY
J 0
(-5435 925);
DISPLAY 0.489362 (-5435 925);
PAINT RED (-5435 925);
FORCEPROP 1 LAST WATTAGE 1/16W
J 0
(-5435 975);
DISPLAY 0.489362 (-5435 975);
PAINT SKYBLUE (-5435 975);
FORCEPROP 2 LAST CDS_LIB pure_quanta
J 0
(-5475 1000);
DISPLAY INVISIBLE (-5475 1000);
FORCEPROP 1 LAST PATH I89
J 0
(-5425 1175);
DISPLAY 0.978723 (-5425 1175);
PAINT WHITE (-5425 1175);
DISPLAY INVISIBLE (-5425 1175);
FORCEPROP 1 LAST PART_NUMBER CS11002FB07
J 0
(-5435 875);
DISPLAY 0.617021 (-5435 875);
PAINT SKYBLUE (-5435 875);
DISPLAY INVISIBLE (-5435 875);
FORCEADD OFFPAGE..1
(-8800 1250);
FORCEPROP 2 LAST $XR0 167 
J 0
(-9052 1250);
DISPLAY 0.638298 (-9052 1250);
PAINT MONO (-9052 1250);
FORCEPROP 2 LAST CDS_LIB standard
J 0
(-8800 1250);
DISPLAY INVISIBLE (-8800 1250);
FORCEPROP 1 LAST OFFPAGE TRUE
J 0
(-8475 1125);
DISPLAY 0.872340 (-8475 1125);
PAINT GREEN (-8475 1125);
DISPLAY INVISIBLE (-8475 1125);
FORCEPROP 1 LAST COMMENT_BODY TRUE
J 0
(-8675 1150);
DISPLAY 0.872340 (-8675 1150);
PAINT GREEN (-8675 1150);
DISPLAY INVISIBLE (-8675 1150);
FORCEPROP 2 LAST PATH I9
J 0
(-9050 1300);
DISPLAY 0.680851 (-9050 1300);
DISPLAY INVISIBLE (-9050 1300);
FORCEADD SW20S_DHNF10FQTR..1
(-7625 1075);
FORCEPROP 1 LAST LOCATION SW1
J 0
(-7725 1450);
DISPLAY 0.723404 (-7725 1450);
PAINT GREEN (-7725 1450);
FORCEPROP 2 LAST SEC 1
J 0
(-7700 1775);
DISPLAY 0.680851 (-7700 1775);
PAINT MONO (-7700 1775);
DISPLAY INVISIBLE (-7700 1775);
FORCEPROP 2 LASTPIN (-7875 1300) $PN 1
J 2
(-7885 1310);
DISPLAY 0.680851 (-7885 1310);
PAINT MONO (-7885 1310);
FORCEPROP 2 LASTPIN (-7875 1250) $PN 2
J 2
(-7885 1260);
DISPLAY 0.680851 (-7885 1260);
PAINT MONO (-7885 1260);
FORCEPROP 2 LASTPIN (-7875 1200) $PN 3
J 2
(-7885 1210);
DISPLAY 0.680851 (-7885 1210);
PAINT MONO (-7885 1210);
FORCEPROP 2 LASTPIN (-7875 1150) $PN 4
J 2
(-7885 1160);
DISPLAY 0.680851 (-7885 1160);
PAINT MONO (-7885 1160);
FORCEPROP 2 LASTPIN (-7875 1100) $PN 5
J 2
(-7885 1110);
DISPLAY 0.680851 (-7885 1110);
PAINT MONO (-7885 1110);
FORCEPROP 2 LASTPIN (-7875 1050) $PN 6
J 2
(-7885 1060);
DISPLAY 0.680851 (-7885 1060);
PAINT MONO (-7885 1060);
FORCEPROP 2 LASTPIN (-7875 1000) $PN 7
J 2
(-7885 1010);
DISPLAY 0.680851 (-7885 1010);
PAINT MONO (-7885 1010);
FORCEPROP 2 LASTPIN (-7875 950) $PN 8
J 2
(-7885 960);
DISPLAY 0.680851 (-7885 960);
PAINT MONO (-7885 960);
FORCEPROP 2 LASTPIN (-7875 900) $PN 9
J 2
(-7885 910);
DISPLAY 0.680851 (-7885 910);
PAINT MONO (-7885 910);
FORCEPROP 2 LASTPIN (-7875 850) $PN 10
J 2
(-7885 860);
DISPLAY 0.680851 (-7885 860);
PAINT MONO (-7885 860);
FORCEPROP 2 LASTPIN (-7375 1300) $PN 11
J 0
(-7365 1310);
DISPLAY 0.680851 (-7365 1310);
PAINT MONO (-7365 1310);
FORCEPROP 2 LASTPIN (-7375 1250) $PN 12
J 0
(-7365 1260);
DISPLAY 0.680851 (-7365 1260);
PAINT MONO (-7365 1260);
FORCEPROP 2 LASTPIN (-7375 1200) $PN 13
J 0
(-7365 1210);
DISPLAY 0.680851 (-7365 1210);
PAINT MONO (-7365 1210);
FORCEPROP 2 LASTPIN (-7375 1150) $PN 14
J 0
(-7365 1160);
DISPLAY 0.680851 (-7365 1160);
PAINT MONO (-7365 1160);
FORCEPROP 2 LASTPIN (-7375 1100) $PN 15
J 0
(-7365 1110);
DISPLAY 0.680851 (-7365 1110);
PAINT MONO (-7365 1110);
FORCEPROP 2 LASTPIN (-7375 1050) $PN 16
J 0
(-7365 1060);
DISPLAY 0.680851 (-7365 1060);
PAINT MONO (-7365 1060);
FORCEPROP 2 LASTPIN (-7375 1000) $PN 17
J 0
(-7365 1010);
DISPLAY 0.680851 (-7365 1010);
PAINT MONO (-7365 1010);
FORCEPROP 2 LASTPIN (-7375 950) $PN 18
J 0
(-7365 960);
DISPLAY 0.680851 (-7365 960);
PAINT MONO (-7365 960);
FORCEPROP 2 LASTPIN (-7375 900) $PN 19
J 0
(-7365 910);
DISPLAY 0.680851 (-7365 910);
PAINT MONO (-7365 910);
FORCEPROP 2 LASTPIN (-7375 850) $PN 20
J 0
(-7365 860);
DISPLAY 0.680851 (-7365 860);
PAINT MONO (-7365 860);
FORCEPROP 1 LAST MATERIAL MECH
J 0
(-7719 1357);
DISPLAY 0.723404 (-7719 1357);
PAINT GREEN (-7719 1357);
FORCEPROP 2 LAST VALUE SW20S_DHNF-10F-Q-T/R
J 0
(-7706 1494);
DISPLAY 0.680851 (-7706 1494);
FORCEPROP 2 LAST PART_TYPE SMLF
J 0
(-7706 1544);
DISPLAY 0.680851 (-7706 1544);
FORCEPROP 1 LAST CDS_LMAN_SYM_OUTLINE -100,275,100,-275
J 0
(-7625 1075);
DISPLAY 0.468085 (-7625 1075);
PAINT GREEN (-7625 1075);
DISPLAY INVISIBLE (-7625 1075);
FORCEPROP 1 LAST NEEDS_NO_SIZE TRUE
J 0
(-7525 840);
DISPLAY 0.723404 (-7525 840);
PAINT GREEN (-7525 840);
DISPLAY INVISIBLE (-7525 840);
FORCEPROP 2 LAST CDS_LIB pure_quanta
J 0
(-7625 1075);
DISPLAY INVISIBLE (-7625 1075);
FORCEPROP 2 LAST SEC_TYPE 
J 0
(-7700 1775);
DISPLAY 0.680851 (-7700 1775);
DISPLAY INVISIBLE (-7700 1775);
FORCEPROP 1 LAST PATH I90
J 0
(-7525 800);
DISPLAY 0.723404 (-7525 800);
PAINT GREEN (-7525 800);
DISPLAY INVISIBLE (-7525 800);
FORCEPROP 1 LAST PART_NUMBER DHD00010F01
J 0
(-7725 1400);
DISPLAY 0.723404 (-7725 1400);
PAINT GREEN (-7725 1400);
DISPLAY INVISIBLE (-7725 1400);
FORCEADD DNS..2
(-4800 1550);
PAINT RED (-4800 1550);
FORCEPROP 2 LAST CDS_LIB mstr_misc
J 0
(-4800 1550);
DISPLAY INVISIBLE (-4800 1550);
FORCEPROP 1 LAST COMMENT_BODY TRUE
R 1
J 0
(-4725 1325);
DISPLAY 0.872340 (-4725 1325);
PAINT GREEN (-4725 1325);
DISPLAY INVISIBLE (-4725 1325);
FORCEADD DNS..2
(-1575 2600);
PAINT RED (-1575 2600);
FORCEPROP 2 LAST CDS_LIB mstr_misc
J 0
(-1575 2600);
DISPLAY INVISIBLE (-1575 2600);
FORCEPROP 1 LAST COMMENT_BODY TRUE
R 1
J 0
(-1500 2375);
DISPLAY 0.872340 (-1500 2375);
PAINT GREEN (-1500 2375);
DISPLAY INVISIBLE (-1500 2375);
FORCEADD DNS..2
(-5050 2450);
PAINT RED (-5050 2450);
FORCEPROP 2 LAST CDS_LIB mstr_misc
J 0
(-5050 2450);
DISPLAY INVISIBLE (-5050 2450);
FORCEPROP 1 LAST COMMENT_BODY TRUE
R 1
J 0
(-4975 2225);
DISPLAY 0.872340 (-4975 2225);
PAINT GREEN (-4975 2225);
DISPLAY INVISIBLE (-4975 2225);
FORCEADD DNS..2
(-5500 1000);
PAINT RED (-5500 1000);
FORCEPROP 2 LAST CDS_LIB mstr_misc
J 0
(-5500 1000);
DISPLAY INVISIBLE (-5500 1000);
FORCEPROP 1 LAST COMMENT_BODY TRUE
R 1
J 0
(-5425 775);
DISPLAY 0.872340 (-5425 775);
PAINT GREEN (-5425 775);
DISPLAY INVISIBLE (-5425 775);
FORCEADD DNS..2
(-4800 4275);
PAINT RED (-4800 4275);
FORCEPROP 2 LAST CDS_LIB mstr_misc
J 0
(-4800 4275);
DISPLAY INVISIBLE (-4800 4275);
FORCEPROP 1 LAST COMMENT_BODY TRUE
R 1
J 0
(-4725 4050);
DISPLAY 0.872340 (-4725 4050);
PAINT GREEN (-4725 4050);
DISPLAY INVISIBLE (-4725 4050);
FORCEADD QUANTA_TITLE_BLOCK_C..1
(0 0);
FORCEPROP 0 LAST CDS_CON_LAST_MODIFIED Thu Sep 14 16:12:15 2023
J 0
(-1885 15);
DISPLAY INVISIBLE (-1885 15);
FORCEPROP 1 LAST CUSTOM_TXT_CDS <CON_LAST_MODIFIED>
J 0
(-1885 15);
DISPLAY 0.978723 (-1885 15);
FORCEPROP 2 LAST CUSTOM_TXT_CDS <XR_PAGE_TITLE>
J 0
(-7890 5250);
DISPLAY 0.638298 (-7890 5250);
PAINT PINK (-7890 5250);
DISPLAY INVISIBLE (-7890 5250);
FORCEPROP 1 LAST CUSTOM_TXT_CDS <NAME_2>
J 0
(-3175 50);
FORCEPROP 1 LAST CUSTOM_TXT_CDS <NAME_1>
J 0
(-3175 175);
FORCEPROP 1 LAST CUSTOM_TXT_CDS <Q_NUMBER>
J 0
(-1403 103);
DISPLAY 1.212766 (-1403 103);
FORCEPROP 1 LAST CUSTOM_TXT_CDS <Q_PROJ>
J 0
(-2382 102);
DISPLAY 1.212766 (-2382 102);
FORCEPROP 1 LAST CUSTOM_TXT_CDS <Q_REV>
J 0
(-184 103);
DISPLAY 1.212766 (-184 103);
FORCEPROP 1 LAST CUSTOM_TXT_CDS <CON_PAGE_NUM> OF <CON_TOTAL_PAGES>
J 0
(-446 18);
DISPLAY 0.978723 (-446 18);
FORCEPROP 1 LAST Q_TITLE DEBUG JUMPER
J 0
(-9275 50);
DISPLAY 2.446809 (-9275 50);
PAINT GREEN (-9275 50);
FORCEPROP 2 LAST PAGE_BORDER TRUE
J 0
(-7890 5250);
DISPLAY 0.638298 (-7890 5250);
PAINT PINK (-7890 5250);
DISPLAY INVISIBLE (-7890 5250);
FORCEPROP 2 LAST CDS_LIB pure_quanta
J 0
(0 0);
DISPLAY INVISIBLE (0 0);
FORCEPROP 1 LAST CDS_LMAN_SYM_OUTLINE -9475,6775,100,-125
J 0
(0 0);
DISPLAY 0.468085 (0 0);
PAINT GREEN (0 0);
DISPLAY INVISIBLE (0 0);
FORCEPROP 2 LAST CDS_XR_PAGE_TITLE CR-167 : @T6G_MB_LIB.T6G(SCH_1):PAGE167
J 0
(-7890 5250);
DISPLAY 0.638298 (-7890 5250);
PAINT PINK (-7890 5250);
DISPLAY INVISIBLE (-7890 5250);
FORCEPROP 1 LAST Q_DEPT BU9
J 1
(-3763 49);
DISPLAY 1.957447 (-3763 49);
PAINT GREEN (-3763 49);
DISPLAY INVISIBLE (-3763 49);
FORCEPROP 1 LAST COMMENT_BODY TRUE
J 0
(12 -13);
DISPLAY 0.978723 (12 -13);
PAINT GREEN (12 -13);
DISPLAY INVISIBLE (12 -13);
WIRE 16 -1 (-8150 1200)(-7875 1200);
WIRE 16 -1 (-8200 5900)(-8200 5950);
WIRE 16 -1 (-8075 2650)(-8075 2700);
WIRE 16 -1 (-7950 3525)(-7950 3475);
WIRE 16 -1 (-4875 975)(-4875 850);
WIRE 16 -1 (-4650 600)(-4750 600);
WIRE 16 -1 (-4750 600)(-4750 550);
WIRE 16 -1 (-8275 900)(-7875 900);
WIRE 16 -1 (-4750 1775)(-4750 1650);
WIRE 16 -1 (-5025 2550)(-5025 2600);
WIRE 16 -1 (-4300 3800)(-4300 3600);
WIRE 16 -1 (-7950 4200)(-7950 4250);
WIRE 16 -1 (-9000 1050)(-9075 1050);
WIRE 16 -1 (-4800 4350)(-4800 4400);
WIRE 16 -1 (-4075 5050)(-4075 5000);
WIRE 16 -1 (-4850 5825)(-4850 5875);
WIRE 16 -1 (-2425 1075)(-2425 875);
WIRE 16 -1 (-2425 1650)(-2425 1700);
WIRE 16 -1 (-1000 1050)(-1000 850);
WIRE 16 -1 (-1000 1625)(-1000 1675);
WIRE 16 -1 (-1525 2700)(-1525 2750);
WIRE 16 -1 (-1775 4300)(-1775 4200);
WIRE 16 -1 (-1775 5950)(-1775 5850);
WIRE 16 -1 (-8150 1300)(-7875 1300);
WIRE 16 -1 (-1100 2700)(-1100 2750);
WIRE 16 -1 (-4600 2550)(-4600 2600);
WIRE 16 -1 (-4500 1650)(-4500 1775);
WIRE 16 -1 (-5475 1175)(-5475 1100);
WIRE 16 -1 (-1100 2500)(-1100 2400);
WIRE 16 -1 (-1100 2400)(-1525 2400);
WIRE 16 -1 (-1525 2500)(-1525 2400);
WIRE 16 -1 (-2250 2400)(-1525 2400);
FORCEPROP 2 LAST SIG_NAME FM_PASSWORD_CLEAR_N
J 0
(-2210 2410);
DISPLAY 0.489362 (-2210 2410);
WIRE 16 -1 (-5725 2250)(-5025 2250);
FORCEPROP 2 LAST SIG_NAME BIOS_DEBUG_MODE
J 0
(-5660 2260);
DISPLAY 0.489362 (-5660 2260);
WIRE 16 -1 (-4600 2250)(-5025 2250);
WIRE 16 -1 (-5025 2250)(-5025 2350);
WIRE 16 -1 (-4600 2350)(-4600 2250);
WIRE 16 -1 (-7950 3725)(-7950 3800);
WIRE 16 -1 (-8600 3800)(-7950 3800);
FORCEPROP 2 LAST SIG_NAME FM_FORCE_ALL_PWRON
J 0
(-8560 3810);
DISPLAY 0.489362 (-8560 3810);
WIRE 16 -1 (-7375 1150)(-6550 1150);
FORCEPROP 2 LAST SIG_NAME FM_BIOS_USB_RECOVERY
J 0
(-7185 1160);
DISPLAY 0.489362 (-7185 1160);
WIRE 16 -1 (-7875 1100)(-8750 1100);
FORCEPROP 2 LAST SIG_NAME PU_FPGA_DEBUG_SW_SPARE
J 0
(-8725 1110);
DISPLAY 0.489362 (-8725 1110);
WIRE 16 -1 (-7875 1050)(-8800 1050);
FORCEPROP 2 LAST SIG_NAME PD_BIOS_DEBUG_MODE
J 0
(-8725 1060);
DISPLAY 0.489362 (-8725 1060);
FORCEPROP 2 LASTPROP $XRERR UNIQUE?
J 0
(-8965 1060);
DISPLAY 0.638298 (-8965 1060);
PAINT MONO (-8965 1060);
DISPLAY INVISIBLE (-8965 1060);
WIRE 16 -1 (-7375 1050)(-6550 1050);
FORCEPROP 2 LAST SIG_NAME BIOS_DEBUG_MODE
J 0
(-7185 1060);
DISPLAY 0.489362 (-7185 1060);
WIRE 16 -1 (-7375 900)(-6550 900);
FORCEPROP 2 LAST SIG_NAME FM_PASSWORD_CLEAR_N
J 0
(-7185 910);
DISPLAY 0.489362 (-7185 910);
WIRE 16 -1 (-6550 850)(-7375 850);
FORCEPROP 2 LAST SIG_NAME FPGA_DEBUG_LED_CTRL
J 0
(-7185 860);
DISPLAY 0.489362 (-7185 860);
WIRE 16 -1 (-8750 850)(-7875 850);
FORCEPROP 2 LAST SIG_NAME PU_FPGA_DEBUG_LED_CTRL
J 0
(-8725 860);
DISPLAY 0.489362 (-8725 860);
WIRE 16 -1 (-1775 5650)(-1775 5450);
WIRE 16 -1 (-1775 5450)(-2325 5450);
FORCEPROP 2 LAST SIG_NAME FM_PRSNT_CPU0_N
J 2
(-1910 5460);
DISPLAY 0.489362 (-1910 5460);
WIRE 16 -1 (-1775 4000)(-1775 3800);
WIRE 16 -1 (-1775 3800)(-2300 3800);
FORCEPROP 2 LAST SIG_NAME FM_PRSNT_CPU1_N
J 2
(-1910 3810);
DISPLAY 0.489362 (-1910 3810);
WIRE 16 -1 (-4850 5525)(-4250 5525);
FORCEPROP 2 LAST SIG_NAME PU_BIOS_USB_RECOVERY
J 0
(-4810 5535);
DISPLAY 0.489362 (-4810 5535);
WIRE 16 -1 (-4850 5525)(-4850 5625);
WIRE 16 -1 (-1725 1250)(-1000 1250);
FORCEPROP 2 LAST SIG_NAME FPGA_DEBUG_LED_CTRL
J 0
(-1685 1260);
DISPLAY 0.489362 (-1685 1260);
WIRE 16 -1 (-8200 5600)(-8200 5700);
WIRE 16 -1 (-8850 5600)(-8200 5600);
FORCEPROP 2 LAST SIG_NAME FM_SPD_CPU0_SWITCH_CTRL_N
J 0
(-8835 5610);
DISPLAY 0.489362 (-8835 5610);
WIRE 16 -1 (-8075 2350)(-8075 2450);
WIRE 16 -1 (-8725 2350)(-8075 2350);
FORCEPROP 2 LAST SIG_NAME BMC_JTAG_SEL
J 0
(-8585 2360);
DISPLAY 0.489362 (-8585 2360);
WIRE 16 -1 (-4075 5250)(-4075 5325);
WIRE 16 -1 (-4875 5325)(-4075 5325);
FORCEPROP 2 LAST SIG_NAME FM_BIOS_USB_RECOVERY
J 0
(-4685 5335);
DISPLAY 0.489362 (-4685 5335);
WIRE 16 -1 (-1000 1425)(-1000 1325);
WIRE 16 -1 (-1725 1325)(-1000 1325);
FORCEPROP 2 LAST SIG_NAME PU_FPGA_DEBUG_LED_CTRL
J 0
(-1685 1335);
DISPLAY 0.489362 (-1685 1335);
WIRE 16 -1 (-3150 1275)(-2425 1275);
FORCEPROP 2 LAST SIG_NAME FPGA_DEBUG_SW_SPARE
J 0
(-3110 1285);
DISPLAY 0.489362 (-3110 1285);
WIRE 16 -1 (-2425 1450)(-2425 1350);
WIRE 16 -1 (-3150 1350)(-2425 1350);
FORCEPROP 2 LAST SIG_NAME PU_FPGA_DEBUG_SW_SPARE
J 0
(-3110 1360);
DISPLAY 0.489362 (-3110 1360);
WIRE 16 -1 (-5625 4000)(-4300 4000);
FORCEPROP 2 LAST SIG_NAME JTAG_BMC_OE
J 0
(-5500 4010);
DISPLAY 0.489362 (-5500 4010);
WIRE 16 -1 (-4300 700)(-3725 700);
FORCEPROP 2 LAST SIG_NAME JTAG_BMC_OE
J 0
(-4160 710);
DISPLAY 0.680851 (-4160 710);
WIRE 16 -1 (-5600 700)(-5475 700);
WIRE 16 -1 (-4650 700)(-5475 700);
FORCEPROP 2 LAST SIG_NAME FM_JTAG_BMC_R_OE
J 0
(-5235 735);
DISPLAY 0.489362 (-5235 735);
WIRE 16 -1 (-5475 900)(-5475 700);
WIRE 16 -1 (-4800 4050)(-4800 4150);
WIRE 16 -1 (-5625 4050)(-4800 4050);
FORCEPROP 2 LAST SIG_NAME FM_JTAG_BMC_R_OE
J 0
(-5500 4060);
DISPLAY 0.489362 (-5500 4060);
WIRE 16 -1 (-7700 525)(-7975 525);
WIRE 16 -1 (-7975 525)(-7975 1000);
WIRE 16 -1 (-7875 1000)(-7975 1000);
WIRE 16 -1 (-7975 1000)(-8750 1000);
FORCEPROP 2 LAST SIG_NAME PRSNT_CPU0_N
J 0
(-8725 1010);
DISPLAY 0.489362 (-8725 1010);
WIRE 16 -1 (-7875 950)(-8100 950);
WIRE 16 -1 (-8100 950)(-8100 300);
WIRE 16 -1 (-8100 950)(-8750 950);
FORCEPROP 2 LAST SIG_NAME PRSNT_CPU1_N
J 0
(-8725 960);
DISPLAY 0.489362 (-8725 960);
WIRE 16 -1 (-8100 300)(-7700 300);
WIRE 16 -1 (-6550 1000)(-7225 1000);
FORCEPROP 2 LAST SIG_NAME FM_PRSNT_CPU0_N
J 0
(-7185 1010);
DISPLAY 0.489362 (-7185 1010);
WIRE 16 -1 (-7225 1000)(-7375 1000);
WIRE 16 -1 (-7225 1000)(-7225 525);
WIRE 16 -1 (-7225 525)(-7500 525);
WIRE 16 -1 (-7375 1250)(-6550 1250);
FORCEPROP 2 LAST SIG_NAME FM_FORCE_ALL_PWRON
J 0
(-7185 1260);
DISPLAY 0.489362 (-7185 1260);
WIRE 16 -1 (-7375 1300)(-6550 1300);
FORCEPROP 2 LAST SIG_NAME FM_SPD_CPU0_SWITCH_CTRL_N
J 0
(-7185 1310);
DISPLAY 0.489362 (-7185 1310);
WIRE 16 -1 (-8750 1250)(-7875 1250);
FORCEPROP 2 LAST SIG_NAME FM_FORCE_ALL_PWRON_ON
J 0
(-8725 1260);
DISPLAY 0.489362 (-8725 1260);
WIRE 16 -1 (-8750 1150)(-7875 1150);
FORCEPROP 2 LAST SIG_NAME PU_BIOS_USB_RECOVERY
J 0
(-8725 1160);
DISPLAY 0.489362 (-8725 1160);
WIRE 16 -1 (-6550 950)(-7075 950);
WIRE 16 -1 (-7075 300)(-7075 950);
WIRE 16 -1 (-7075 950)(-7375 950);
FORCEPROP 2 LAST SIG_NAME FM_PRSNT_CPU1_N
J 0
(-7185 960);
DISPLAY 0.489362 (-7185 960);
WIRE 16 -1 (-7500 300)(-7075 300);
WIRE 16 -1 (-6550 1100)(-7375 1100);
FORCEPROP 2 LAST SIG_NAME FPGA_DEBUG_SW_SPARE
J 0
(-7185 1110);
DISPLAY 0.489362 (-7185 1110);
WIRE 16 -1 (-7375 1200)(-6550 1200);
FORCEPROP 2 LAST SIG_NAME BMC_JTAG_SEL
J 0
(-7185 1210);
DISPLAY 0.489362 (-7185 1210);
WIRE 16 -1 (-4875 1175)(-4875 1250);
WIRE 16 -1 (-4875 1250)(-4750 1250);
WIRE 16 -1 (-4500 1250)(-4750 1250);
FORCEPROP 2 LAST SIG_NAME U124_VCC
J 0
(-4735 1285);
DISPLAY 0.553191 (-4735 1285);
FORCEPROP 2 LASTPROP $XRERR UNIQUE?
J 0
(-4975 1285);
DISPLAY 0.638298 (-4975 1285);
PAINT MONO (-4975 1285);
DISPLAY INVISIBLE (-4975 1285);
WIRE 16 -1 (-4750 1450)(-4750 1250);
WIRE 16 -1 (-4750 800)(-4750 1250);
WIRE 16 -1 (-4650 800)(-4750 800);
WIRE 16 -1 (-4500 1450)(-4500 1250);
WIRE 16 -1 (-7950 3900)(-7950 4000);
WIRE 16 -1 (-8600 3900)(-7950 3900);
FORCEPROP 2 LAST SIG_NAME FM_FORCE_ALL_PWRON_ON
J 0
(-8560 3910);
DISPLAY 0.489362 (-8560 3910);
DOT 1 (-5025 2250);
DOT 1 (-8100 950);
DOT 1 (-7975 1000);
DOT 1 (-7225 1000);
DOT 1 (-1525 2400);
DOT 1 (-7075 950);
DOT 1 (-5475 700);
DOT 1 (-4750 1250);
FORCENOTE
ON: PASSWORD CLEAR
(-2775 2925) 0;
DISPLAY LEFT (-2775 2925);
DISPLAY 1.595745 (-2775 2925);
FORCENOTE
OFF: NORMAL (DEFAULT)
(-2775 3050) 0;
DISPLAY LEFT (-2775 3050);
DISPLAY 1.595745 (-2775 3050);
FORCENOTE
OFF: ENABLE JTAG MUX TO PLD (DEFAULT)
(-9100 3025) 0;
DISPLAY LEFT (-9100 3025);
DISPLAY 1.595745 (-9100 3025);
FORCENOTE
SWITCH DEFAULT IS OFF
(-8075 675) 0;
DISPLAY LEFT (-8075 675);
DISPLAY 1.021277 (-8075 675);
PAINT WHITE (-8075 675);
FORCENOTE
FPGA_DEBUG_LED_CTRL
(-2150 1675) 0;
DISPLAY LEFT (-2150 1675);
DISPLAY 1.021277 (-2150 1675);
FORCENOTE
OFF:POST LED(DEFAULT)
(-2150 1600) 0;
DISPLAY LEFT (-2150 1600);
DISPLAY 1.021277 (-2150 1600);
FORCENOTE
ON: DISABLE CPU1 DEBUG
(-2825 4600) 0;
DISPLAY LEFT (-2825 4600);
DISPLAY 1.595745 (-2825 4600);
FORCENOTE
OFF: CPU1 PRESENT FOR DEBUG (DEFAULT)
(-2825 4725) 0;
DISPLAY LEFT (-2825 4725);
DISPLAY 1.595745 (-2825 4725);
FORCENOTE
CPU1 BYPASS CHAIN CONTROL
(-2825 4825) 0;
DISPLAY LEFT (-2825 4825);
DISPLAY 1.595745 (-2825 4825);
FORCENOTE
ON: BMC SPD REMOTE DEBUG ENABLED
(-9100 6125) 0;
DISPLAY LEFT (-9100 6125);
DISPLAY 1.276596 (-9100 6125);
FORCENOTE
BMC JTAG SEL
(-9100 3150) 0;
DISPLAY LEFT (-9100 3150);
DISPLAY 1.595745 (-9100 3150);
FORCENOTE
ON: ENABLE ALL POWER ON
(-9100 4575) 0;
DISPLAY LEFT (-9100 4575);
DISPLAY 1.595745 (-9100 4575);
FORCENOTE
FORCE POWER ON 
(-9100 4825) 0;
DISPLAY LEFT (-9100 4825);
DISPLAY 1.595745 (-9100 4825);
FORCENOTE
OFF: BMC SPD REMOTE DEBUG DISABLED (DEFAULT)
(-9100 6225) 0;
DISPLAY LEFT (-9100 6225);
DISPLAY 1.276596 (-9100 6225);
FORCENOTE
BMC SPD REMOTE DEBUG
(-9100 6325) 0;
DISPLAY LEFT (-9100 6325);
DISPLAY 1.276596 (-9100 6325);
FORCENOTE
BIOS USB RECOVERY
(-5925 6325) 0;
DISPLAY LEFT (-5925 6325);
DISPLAY 1.595745 (-5925 6325);
FORCENOTE
CPU0 BYPASS CHAIN CONTROL
(-2900 6325) 0;
DISPLAY LEFT (-2900 6325);
DISPLAY 1.595745 (-2900 6325);
FORCENOTE
OFF: CPU0 PRESENT FOR DEBUG (DEFAULT)
(-2900 6225) 0;
DISPLAY LEFT (-2900 6225);
DISPLAY 1.595745 (-2900 6225);
FORCENOTE
ON: DISABLE CPU0 DEBUG
(-2900 6100) 0;
DISPLAY LEFT (-2900 6100);
DISPLAY 1.595745 (-2900 6100);
FORCENOTE
HW ASD EN
(-5850 4800) 0;
DISPLAY LEFT (-5850 4800);
DISPLAY 1.595745 (-5850 4800);
FORCENOTE
ON: NORMAL OPERATION (DEFAULT)
(-5925 6075) 0;
DISPLAY LEFT (-5925 6075);
DISPLAY 1.595745 (-5925 6075);
FORCENOTE
OFF: BIOS USB FLASH RECOVERY MODE
(-5925 6200) 0;
DISPLAY LEFT (-5925 6200);
DISPLAY 1.595745 (-5925 6200);
FORCENOTE
PASSWORD CLEAR
(-2775 3150) 0;
DISPLAY LEFT (-2775 3150);
DISPLAY 1.595745 (-2775 3150);
FORCENOTE
ON:FPGA_DEBUG_LED
(-2150 1525) 0;
DISPLAY LEFT (-2150 1525);
DISPLAY 1.021277 (-2150 1525);
FORCENOTE
BIOS RECOVERY
(-5900 3100) 0;
DISPLAY LEFT (-5900 3100);
DISPLAY 1.595745 (-5900 3100);
FORCENOTE
OFF: BIOS USB FLASH RECOVERY MODE
(-5900 2975) 0;
DISPLAY LEFT (-5900 2975);
DISPLAY 1.595745 (-5900 2975);
FORCENOTE
ON: NORMAL OPERATION (DEFAULT)
(-5900 2825) 0;
DISPLAY LEFT (-5900 2825);
DISPLAY 1.595745 (-5900 2825);
FORCENOTE
ON:FRU
(-3675 1525) 0;
DISPLAY LEFT (-3675 1525);
DISPLAY 1.021277 (-3675 1525);
FORCENOTE
OFF:NORMAL(DEFAULT)
(-3675 1591) 0;
DISPLAY LEFT (-3675 1591);
DISPLAY 1.021277 (-3675 1591);
FORCENOTE
SWITCH DEFAULT IS OFF
(-3675 1657) 0;
DISPLAY LEFT (-3675 1657);
DISPLAY 1.021277 (-3675 1657);
FORCENOTE
FPGA_DEBUG_SW_SPARE
(-3675 1723) 0;
DISPLAY LEFT (-3675 1723);
DISPLAY 1.021277 (-3675 1723);
FORCENOTE
OFF: DISABLE ALL POWER ON (DEFAULT)
(-9100 4700) 0;
DISPLAY LEFT (-9100 4700);
DISPLAY 1.595745 (-9100 4700);
FORCENOTE
OFF: ENABLE REMOTE DEBUG
(-5850 4700) 0;
DISPLAY LEFT (-5850 4700);
DISPLAY 1.595745 (-5850 4700);
FORCENOTE
ON: DISABLE REMOTE DEBUG (DEFAULT) 
(-5850 4600) 0;
DISPLAY LEFT (-5850 4600);
DISPLAY 1.595745 (-5850 4600);
FORCENOTE
ON: ENABLE JTAG MUX TO HDT
(-9100 2900) 0;
DISPLAY LEFT (-9100 2900);
DISPLAY 1.595745 (-9100 2900);
QUIT
